(kicad_sch
	(version 20250114)
	(generator "eeschema")
	(generator_version "9.0")
	(paper "A3")
	(title_block
		(title "Kintex 410T devboard")
		(date "2024-04-03")
		(rev "1.1.2")
	)
	(text "Master SPI Quad (x4) configuration scheme"
		(exclude_from_sim no)
		(at 31.115 38.735 0)
		(effects
			(font
				(size 1.27 1.27)
				(thickness 0.5994)
				(bold yes)
			)
			(justify left bottom)
		)
	)
	(text "(Q)SPI flash"
		(exclude_from_sim no)
		(at 13.97 17.78 0)
		(effects
			(font
				(size 1.27 1.27)
				(thickness 0.5994)
				(bold yes)
			)
			(justify left bottom)
		)
	)
	(text "USER SD CARD"
		(exclude_from_sim no)
		(at 211.455 17.78 0)
		(effects
			(font
				(size 1.27 1.27)
				(thickness 0.5994)
				(bold yes)
			)
			(justify left bottom)
		)
	)
	(text "USER SPI flash 1"
		(exclude_from_sim no)
		(at 210.82 138.43 0)
		(effects
			(font
				(size 1.27 1.27)
				(thickness 0.5994)
				(bold yes)
			)
			(justify left bottom)
		)
	)
	(text "USER SPI flash 0"
		(exclude_from_sim no)
		(at 13.335 138.43 0)
		(effects
			(font
				(size 1.27 1.27)
				(thickness 0.5994)
				(bold yes)
			)
			(justify left bottom)
		)
	)
	(text "Follows Figure 2-14 7 Series FPGAs Configuration User Guide\nUG470 (v1.15)"
		(exclude_from_sim no)
		(at 31.115 44.45 0)
		(effects
			(font
				(size 1.27 1.27)
			)
			(justify left bottom)
		)
	)
	(junction
		(at 226.06 83.82)
		(diameter 0)
		(color 0 0 0 0)
	)
	(junction
		(at 83.82 196.85)
		(diameter 0)
		(color 0 0 0 0)
	)
	(junction
		(at 295.91 186.69)
		(diameter 0)
		(color 0 0 0 0)
	)
	(junction
		(at 175.26 78.74)
		(diameter 0)
		(color 0 0 0 0)
	)
	(junction
		(at 226.06 76.2)
		(diameter 0)
		(color 0 0 0 0)
	)
	(junction
		(at 74.93 53.34)
		(diameter 0)
		(color 0 0 0 0)
	)
	(junction
		(at 83.82 76.2)
		(diameter 0)
		(color 0 0 0 0)
	)
	(junction
		(at 101.6 68.58)
		(diameter 0)
		(color 0 0 0 0)
	)
	(junction
		(at 92.71 186.69)
		(diameter 0)
		(color 0 0 0 0)
	)
	(junction
		(at 74.93 78.74)
		(diameter 0)
		(color 0 0 0 0)
	)
	(junction
		(at 177.8 66.04)
		(diameter 0)
		(color 0 0 0 0)
	)
	(junction
		(at 175.26 199.39)
		(diameter 0)
		(color 0 0 0 0)
	)
	(junction
		(at 177.8 78.74)
		(diameter 0)
		(color 0 0 0 0)
	)
	(junction
		(at 101.6 189.23)
		(diameter 0)
		(color 0 0 0 0)
	)
	(junction
		(at 74.93 199.39)
		(diameter 0)
		(color 0 0 0 0)
	)
	(junction
		(at 295.91 173.99)
		(diameter 0)
		(color 0 0 0 0)
	)
	(junction
		(at 278.13 173.99)
		(diameter 0)
		(color 0 0 0 0)
	)
	(junction
		(at 382.27 186.69)
		(diameter 0)
		(color 0 0 0 0)
	)
	(junction
		(at 392.43 99.06)
		(diameter 0)
		(color 0 0 0 0)
	)
	(junction
		(at 74.93 173.99)
		(diameter 0)
		(color 0 0 0 0)
	)
	(junction
		(at 304.8 189.23)
		(diameter 0)
		(color 0 0 0 0)
	)
	(junction
		(at 379.73 199.39)
		(diameter 0)
		(color 0 0 0 0)
	)
	(junction
		(at 83.82 173.99)
		(diameter 0)
		(color 0 0 0 0)
	)
	(junction
		(at 340.36 88.9)
		(diameter 0)
		(color 0 0 0 0)
	)
	(junction
		(at 226.06 66.04)
		(diameter 0)
		(color 0 0 0 0)
	)
	(junction
		(at 226.06 71.12)
		(diameter 0)
		(color 0 0 0 0)
	)
	(junction
		(at 177.8 186.69)
		(diameter 0)
		(color 0 0 0 0)
	)
	(junction
		(at 83.82 53.34)
		(diameter 0)
		(color 0 0 0 0)
	)
	(junction
		(at 92.71 173.99)
		(diameter 0)
		(color 0 0 0 0)
	)
	(junction
		(at 326.39 49.53)
		(diameter 0)
		(color 0 0 0 0)
	)
	(junction
		(at 226.06 81.28)
		(diameter 0)
		(color 0 0 0 0)
	)
	(junction
		(at 287.02 173.99)
		(diameter 0)
		(color 0 0 0 0)
	)
	(junction
		(at 278.13 199.39)
		(diameter 0)
		(color 0 0 0 0)
	)
	(junction
		(at 226.06 68.58)
		(diameter 0)
		(color 0 0 0 0)
	)
	(junction
		(at 92.71 53.34)
		(diameter 0)
		(color 0 0 0 0)
	)
	(junction
		(at 92.71 66.04)
		(diameter 0)
		(color 0 0 0 0)
	)
	(junction
		(at 287.02 196.85)
		(diameter 0)
		(color 0 0 0 0)
	)
	(junction
		(at 388.62 88.9)
		(diameter 0)
		(color 0 0 0 0)
	)
	(no_connect
		(at 293.37 78.74)
	)
	(no_connect
		(at 293.37 73.66)
	)
	(no_connect
		(at 303.53 73.66)
	)
	(no_connect
		(at 303.53 78.74)
	)
	(bus_entry
		(at 53.34 69.85)
		(size 1.27 -1.27)
		(stroke
			(width 0)
			(type default)
		)
	)
	(bus_entry
		(at 266.7 69.85)
		(size -1.27 -1.27)
		(stroke
			(width 0)
			(type default)
		)
	)
	(bus_entry
		(at 53.34 77.47)
		(size 1.27 -1.27)
		(stroke
			(width 0)
			(type default)
		)
	)
	(bus_entry
		(at 53.34 193.04)
		(size 1.27 -1.27)
		(stroke
			(width 0)
			(type default)
		)
	)
	(bus_entry
		(at 53.34 187.96)
		(size 1.27 -1.27)
		(stroke
			(width 0)
			(type default)
		)
	)
	(bus_entry
		(at 266.7 77.47)
		(size -1.27 -1.27)
		(stroke
			(width 0)
			(type default)
		)
	)
	(bus_entry
		(at 53.34 80.01)
		(size 1.27 -1.27)
		(stroke
			(width 0)
			(type default)
		)
	)
	(bus_entry
		(at 53.34 200.66)
		(size 1.27 -1.27)
		(stroke
			(width 0)
			(type default)
		)
	)
	(bus_entry
		(at 257.81 187.96)
		(size 1.27 -1.27)
		(stroke
			(width 0)
			(type default)
		)
	)
	(bus_entry
		(at 266.7 72.39)
		(size -1.27 -1.27)
		(stroke
			(width 0)
			(type default)
		)
	)
	(bus_entry
		(at 53.34 74.93)
		(size 1.27 -1.27)
		(stroke
			(width 0)
			(type default)
		)
	)
	(bus_entry
		(at 266.7 85.09)
		(size 1.27 -1.27)
		(stroke
			(width 0)
			(type default)
		)
	)
	(bus_entry
		(at 53.34 67.31)
		(size 1.27 -1.27)
		(stroke
			(width 0)
			(type default)
		)
	)
	(bus_entry
		(at 53.34 69.85)
		(size 1.27 -1.27)
		(stroke
			(width 0)
			(type default)
		)
	)
	(bus_entry
		(at 257.81 193.04)
		(size 1.27 -1.27)
		(stroke
			(width 0)
			(type default)
		)
	)
	(bus_entry
		(at 266.7 87.63)
		(size 1.27 -1.27)
		(stroke
			(width 0)
			(type default)
		)
	)
	(bus_entry
		(at 266.7 69.85)
		(size 1.27 -1.27)
		(stroke
			(width 0)
			(type default)
		)
	)
	(bus_entry
		(at 257.81 200.66)
		(size 1.27 -1.27)
		(stroke
			(width 0)
			(type default)
		)
	)
	(bus_entry
		(at 257.81 190.5)
		(size 1.27 -1.27)
		(stroke
			(width 0)
			(type default)
		)
	)
	(bus_entry
		(at 266.7 72.39)
		(size 1.27 -1.27)
		(stroke
			(width 0)
			(type default)
		)
	)
	(bus_entry
		(at 257.81 198.12)
		(size 1.27 -1.27)
		(stroke
			(width 0)
			(type default)
		)
	)
	(bus_entry
		(at 266.7 82.55)
		(size 1.27 -1.27)
		(stroke
			(width 0)
			(type default)
		)
	)
	(bus_entry
		(at 257.81 195.58)
		(size 1.27 -1.27)
		(stroke
			(width 0)
			(type default)
		)
	)
	(bus_entry
		(at 53.34 190.5)
		(size 1.27 -1.27)
		(stroke
			(width 0)
			(type default)
		)
	)
	(bus_entry
		(at 53.34 72.39)
		(size 1.27 -1.27)
		(stroke
			(width 0)
			(type default)
		)
	)
	(bus_entry
		(at 266.7 85.09)
		(size -1.27 -1.27)
		(stroke
			(width 0)
			(type default)
		)
	)
	(bus_entry
		(at 266.7 82.55)
		(size -1.27 -1.27)
		(stroke
			(width 0)
			(type default)
		)
	)
	(bus_entry
		(at 53.34 198.12)
		(size 1.27 -1.27)
		(stroke
			(width 0)
			(type default)
		)
	)
	(bus_entry
		(at 266.7 67.31)
		(size 1.27 -1.27)
		(stroke
			(width 0)
			(type default)
		)
	)
	(bus_entry
		(at 266.7 67.31)
		(size -1.27 -1.27)
		(stroke
			(width 0)
			(type default)
		)
	)
	(bus_entry
		(at 53.34 195.58)
		(size 1.27 -1.27)
		(stroke
			(width 0)
			(type default)
		)
	)
	(bus_entry
		(at 266.7 77.47)
		(size 1.27 -1.27)
		(stroke
			(width 0)
			(type default)
		)
	)
	(bus_entry
		(at 266.7 87.63)
		(size -1.27 -1.27)
		(stroke
			(width 0)
			(type default)
		)
	)
	(bus
		(pts
			(xy 53.34 203.2) (xy 50.8 205.74)
		)
		(stroke
			(width 0)
			(type default)
		)
	)
	(wire
		(pts
			(xy 83.82 196.85) (xy 111.76 196.85)
		)
		(stroke
			(width 0)
			(type default)
		)
	)
	(bus
		(pts
			(xy 53.34 187.96) (xy 53.34 190.5)
		)
		(stroke
			(width 0)
			(type default)
		)
	)
	(wire
		(pts
			(xy 177.8 186.69) (xy 182.88 186.69)
		)
		(stroke
			(width 0)
			(type default)
		)
	)
	(wire
		(pts
			(xy 392.43 99.06) (xy 392.43 100.33)
		)
		(stroke
			(width 0)
			(type default)
		)
	)
	(wire
		(pts
			(xy 340.36 88.9) (xy 340.36 90.17)
		)
		(stroke
			(width 0)
			(type default)
		)
	)
	(wire
		(pts
			(xy 74.93 53.34) (xy 83.82 53.34)
		)
		(stroke
			(width 0)
			(type default)
		)
	)
	(wire
		(pts
			(xy 233.68 76.2) (xy 226.06 76.2)
		)
		(stroke
			(width 0)
			(type default)
		)
	)
	(wire
		(pts
			(xy 173.99 78.74) (xy 175.26 78.74)
		)
		(stroke
			(width 0)
			(type default)
		)
	)
	(wire
		(pts
			(xy 378.46 196.85) (xy 379.73 196.85)
		)
		(stroke
			(width 0)
			(type default)
		)
	)
	(bus
		(pts
			(xy 53.34 198.12) (xy 53.34 200.66)
		)
		(stroke
			(width 0)
			(type default)
		)
	)
	(bus
		(pts
			(xy 53.34 77.47) (xy 53.34 80.01)
		)
		(stroke
			(width 0)
			(type default)
		)
	)
	(wire
		(pts
			(xy 392.43 99.06) (xy 388.62 99.06)
		)
		(stroke
			(width 0)
			(type default)
		)
	)
	(bus
		(pts
			(xy 257.81 203.2) (xy 255.27 205.74)
		)
		(stroke
			(width 0)
			(type default)
		)
	)
	(wire
		(pts
			(xy 233.68 83.82) (xy 226.06 83.82)
		)
		(stroke
			(width 0)
			(type default)
		)
	)
	(wire
		(pts
			(xy 226.06 83.82) (xy 226.06 86.36)
		)
		(stroke
			(width 0)
			(type default)
		)
	)
	(wire
		(pts
			(xy 175.26 196.85) (xy 175.26 199.39)
		)
		(stroke
			(width 0)
			(type default)
		)
	)
	(wire
		(pts
			(xy 259.08 196.85) (xy 287.02 196.85)
		)
		(stroke
			(width 0)
			(type default)
		)
	)
	(bus
		(pts
			(xy 45.72 85.09) (xy 52.07 85.09)
		)
		(stroke
			(width 0)
			(type default)
		)
	)
	(wire
		(pts
			(xy 74.93 53.34) (xy 74.93 55.88)
		)
		(stroke
			(width 0)
			(type default)
		)
	)
	(wire
		(pts
			(xy 177.8 199.39) (xy 175.26 199.39)
		)
		(stroke
			(width 0)
			(type default)
		)
	)
	(polyline
		(pts
			(xy 203.2 13.97) (xy 203.2 127)
		)
		(stroke
			(width 0)
			(type default)
		)
	)
	(wire
		(pts
			(xy 278.13 181.61) (xy 278.13 199.39)
		)
		(stroke
			(width 0)
			(type default)
		)
	)
	(wire
		(pts
			(xy 304.8 208.28) (xy 304.8 209.55)
		)
		(stroke
			(width 0)
			(type default)
		)
	)
	(bus
		(pts
			(xy 53.34 67.31) (xy 53.34 69.85)
		)
		(stroke
			(width 0)
			(type default)
		)
	)
	(wire
		(pts
			(xy 278.13 173.99) (xy 287.02 173.99)
		)
		(stroke
			(width 0)
			(type default)
		)
	)
	(wire
		(pts
			(xy 379.73 196.85) (xy 379.73 199.39)
		)
		(stroke
			(width 0)
			(type default)
		)
	)
	(bus
		(pts
			(xy 266.7 91.44) (xy 265.43 92.71)
		)
		(stroke
			(width 0)
			(type default)
		)
	)
	(wire
		(pts
			(xy 101.6 189.23) (xy 111.76 189.23)
		)
		(stroke
			(width 0)
			(type default)
		)
	)
	(bus
		(pts
			(xy 266.7 77.47) (xy 266.7 82.55)
		)
		(stroke
			(width 0)
			(type default)
		)
	)
	(wire
		(pts
			(xy 303.53 68.58) (xy 344.17 68.58)
		)
		(stroke
			(width 0)
			(type default)
		)
	)
	(wire
		(pts
			(xy 265.43 71.12) (xy 238.76 71.12)
		)
		(stroke
			(width 0)
			(type default)
		)
	)
	(wire
		(pts
			(xy 116.84 199.39) (xy 146.05 199.39)
		)
		(stroke
			(width 0)
			(type default)
		)
	)
	(wire
		(pts
			(xy 226.06 64.77) (xy 226.06 66.04)
		)
		(stroke
			(width 0)
			(type default)
		)
	)
	(wire
		(pts
			(xy 173.99 76.2) (xy 175.26 76.2)
		)
		(stroke
			(width 0)
			(type default)
		)
	)
	(wire
		(pts
			(xy 233.68 66.04) (xy 226.06 66.04)
		)
		(stroke
			(width 0)
			(type default)
		)
	)
	(wire
		(pts
			(xy 74.93 172.72) (xy 74.93 173.99)
		)
		(stroke
			(width 0)
			(type default)
		)
	)
	(wire
		(pts
			(xy 54.61 191.77) (xy 111.76 191.77)
		)
		(stroke
			(width 0)
			(type default)
		)
	)
	(bus
		(pts
			(xy 257.81 195.58) (xy 257.81 198.12)
		)
		(stroke
			(width 0)
			(type default)
		)
	)
	(wire
		(pts
			(xy 267.97 81.28) (xy 293.37 81.28)
		)
		(stroke
			(width 0)
			(type default)
		)
	)
	(wire
		(pts
			(xy 396.24 88.9) (xy 396.24 91.44)
		)
		(stroke
			(width 0)
			(type default)
		)
	)
	(wire
		(pts
			(xy 267.97 76.2) (xy 293.37 76.2)
		)
		(stroke
			(width 0)
			(type default)
		)
	)
	(wire
		(pts
			(xy 388.62 88.9) (xy 388.62 91.44)
		)
		(stroke
			(width 0)
			(type default)
		)
	)
	(wire
		(pts
			(xy 177.8 195.58) (xy 177.8 199.39)
		)
		(stroke
			(width 0)
			(type default)
		)
	)
	(wire
		(pts
			(xy 265.43 68.58) (xy 238.76 68.58)
		)
		(stroke
			(width 0)
			(type default)
		)
	)
	(wire
		(pts
			(xy 74.93 173.99) (xy 83.82 173.99)
		)
		(stroke
			(width 0)
			(type default)
		)
	)
	(wire
		(pts
			(xy 226.06 66.04) (xy 226.06 68.58)
		)
		(stroke
			(width 0)
			(type default)
		)
	)
	(wire
		(pts
			(xy 303.53 71.12) (xy 344.17 71.12)
		)
		(stroke
			(width 0)
			(type default)
		)
	)
	(wire
		(pts
			(xy 267.97 83.82) (xy 293.37 83.82)
		)
		(stroke
			(width 0)
			(type default)
		)
	)
	(wire
		(pts
			(xy 175.26 78.74) (xy 177.8 78.74)
		)
		(stroke
			(width 0)
			(type default)
		)
	)
	(wire
		(pts
			(xy 391.16 185.42) (xy 391.16 186.69)
		)
		(stroke
			(width 0)
			(type default)
		)
	)
	(wire
		(pts
			(xy 304.8 181.61) (xy 304.8 189.23)
		)
		(stroke
			(width 0)
			(type default)
		)
	)
	(wire
		(pts
			(xy 259.08 186.69) (xy 295.91 186.69)
		)
		(stroke
			(width 0)
			(type default)
		)
	)
	(bus
		(pts
			(xy 257.81 193.04) (xy 257.81 195.58)
		)
		(stroke
			(width 0)
			(type default)
		)
	)
	(wire
		(pts
			(xy 321.31 189.23) (xy 350.52 189.23)
		)
		(stroke
			(width 0)
			(type default)
		)
	)
	(wire
		(pts
			(xy 259.08 199.39) (xy 278.13 199.39)
		)
		(stroke
			(width 0)
			(type default)
		)
	)
	(wire
		(pts
			(xy 265.43 83.82) (xy 238.76 83.82)
		)
		(stroke
			(width 0)
			(type default)
		)
	)
	(wire
		(pts
			(xy 101.6 208.28) (xy 101.6 209.55)
		)
		(stroke
			(width 0)
			(type default)
		)
	)
	(wire
		(pts
			(xy 259.08 189.23) (xy 304.8 189.23)
		)
		(stroke
			(width 0)
			(type default)
		)
	)
	(wire
		(pts
			(xy 182.88 64.77) (xy 182.88 66.04)
		)
		(stroke
			(width 0)
			(type default)
		)
	)
	(wire
		(pts
			(xy 74.93 60.96) (xy 74.93 78.74)
		)
		(stroke
			(width 0)
			(type default)
		)
	)
	(wire
		(pts
			(xy 321.31 194.31) (xy 350.52 194.31)
		)
		(stroke
			(width 0)
			(type default)
		)
	)
	(bus
		(pts
			(xy 53.34 74.93) (xy 53.34 77.47)
		)
		(stroke
			(width 0)
			(type default)
		)
	)
	(wire
		(pts
			(xy 233.68 86.36) (xy 226.06 86.36)
		)
		(stroke
			(width 0)
			(type default)
		)
	)
	(wire
		(pts
			(xy 226.06 83.82) (xy 226.06 81.28)
		)
		(stroke
			(width 0)
			(type default)
		)
	)
	(bus
		(pts
			(xy 266.7 82.55) (xy 266.7 85.09)
		)
		(stroke
			(width 0)
			(type default)
		)
	)
	(wire
		(pts
			(xy 344.17 78.74) (xy 340.36 78.74)
		)
		(stroke
			(width 0)
			(type default)
		)
	)
	(bus
		(pts
			(xy 53.34 80.01) (xy 53.34 83.82)
		)
		(stroke
			(width 0)
			(type default)
		)
	)
	(wire
		(pts
			(xy 175.26 199.39) (xy 173.99 199.39)
		)
		(stroke
			(width 0)
			(type default)
		)
	)
	(bus
		(pts
			(xy 53.34 83.82) (xy 52.07 85.09)
		)
		(stroke
			(width 0)
			(type default)
		)
	)
	(bus
		(pts
			(xy 53.34 190.5) (xy 53.34 193.04)
		)
		(stroke
			(width 0)
			(type default)
		)
	)
	(wire
		(pts
			(xy 83.82 173.99) (xy 83.82 176.53)
		)
		(stroke
			(width 0)
			(type default)
		)
	)
	(polyline
		(pts
			(xy 209.55 13.97) (xy 209.55 127)
		)
		(stroke
			(width 0)
			(type default)
		)
	)
	(bus
		(pts
			(xy 266.7 67.31) (xy 266.7 69.85)
		)
		(stroke
			(width 0)
			(type default)
		)
	)
	(wire
		(pts
			(xy 54.61 199.39) (xy 74.93 199.39)
		)
		(stroke
			(width 0)
			(type default)
		)
	)
	(wire
		(pts
			(xy 303.53 66.04) (xy 344.17 66.04)
		)
		(stroke
			(width 0)
			(type default)
		)
	)
	(wire
		(pts
			(xy 303.53 76.2) (xy 344.17 76.2)
		)
		(stroke
			(width 0)
			(type default)
		)
	)
	(wire
		(pts
			(xy 92.71 53.34) (xy 92.71 55.88)
		)
		(stroke
			(width 0)
			(type default)
		)
	)
	(wire
		(pts
			(xy 83.82 53.34) (xy 92.71 53.34)
		)
		(stroke
			(width 0)
			(type default)
		)
	)
	(wire
		(pts
			(xy 101.6 68.58) (xy 110.49 68.58)
		)
		(stroke
			(width 0)
			(type default)
		)
	)
	(wire
		(pts
			(xy 278.13 199.39) (xy 316.23 199.39)
		)
		(stroke
			(width 0)
			(type default)
		)
	)
	(wire
		(pts
			(xy 378.46 186.69) (xy 382.27 186.69)
		)
		(stroke
			(width 0)
			(type default)
		)
	)
	(wire
		(pts
			(xy 388.62 99.06) (xy 388.62 96.52)
		)
		(stroke
			(width 0)
			(type default)
		)
	)
	(wire
		(pts
			(xy 74.93 199.39) (xy 111.76 199.39)
		)
		(stroke
			(width 0)
			(type default)
		)
	)
	(wire
		(pts
			(xy 101.6 60.96) (xy 101.6 68.58)
		)
		(stroke
			(width 0)
			(type default)
		)
	)
	(bus
		(pts
			(xy 257.81 187.96) (xy 257.81 190.5)
		)
		(stroke
			(width 0)
			(type default)
		)
	)
	(polyline
		(pts
			(xy 406.4 133.35) (xy 209.55 133.35)
		)
		(stroke
			(width 0)
			(type default)
		)
	)
	(wire
		(pts
			(xy 177.8 186.69) (xy 177.8 190.5)
		)
		(stroke
			(width 0)
			(type default)
		)
	)
	(wire
		(pts
			(xy 101.6 53.34) (xy 101.6 55.88)
		)
		(stroke
			(width 0)
			(type default)
		)
	)
	(wire
		(pts
			(xy 101.6 68.58) (xy 101.6 82.55)
		)
		(stroke
			(width 0)
			(type default)
		)
	)
	(wire
		(pts
			(xy 226.06 76.2) (xy 226.06 81.28)
		)
		(stroke
			(width 0)
			(type default)
		)
	)
	(wire
		(pts
			(xy 83.82 53.34) (xy 83.82 55.88)
		)
		(stroke
			(width 0)
			(type default)
		)
	)
	(wire
		(pts
			(xy 304.8 189.23) (xy 316.23 189.23)
		)
		(stroke
			(width 0)
			(type default)
		)
	)
	(wire
		(pts
			(xy 326.39 49.53) (xy 340.36 49.53)
		)
		(stroke
			(width 0)
			(type default)
		)
	)
	(wire
		(pts
			(xy 303.53 81.28) (xy 344.17 81.28)
		)
		(stroke
			(width 0)
			(type default)
		)
	)
	(wire
		(pts
			(xy 382.27 195.58) (xy 382.27 199.39)
		)
		(stroke
			(width 0)
			(type default)
		)
	)
	(wire
		(pts
			(xy 173.99 66.04) (xy 177.8 66.04)
		)
		(stroke
			(width 0)
			(type default)
		)
	)
	(wire
		(pts
			(xy 175.26 76.2) (xy 175.26 78.74)
		)
		(stroke
			(width 0)
			(type default)
		)
	)
	(wire
		(pts
			(xy 116.84 191.77) (xy 146.05 191.77)
		)
		(stroke
			(width 0)
			(type default)
		)
	)
	(wire
		(pts
			(xy 295.91 173.99) (xy 304.8 173.99)
		)
		(stroke
			(width 0)
			(type default)
		)
	)
	(wire
		(pts
			(xy 340.36 73.66) (xy 344.17 73.66)
		)
		(stroke
			(width 0)
			(type default)
		)
	)
	(wire
		(pts
			(xy 396.24 96.52) (xy 396.24 99.06)
		)
		(stroke
			(width 0)
			(type default)
		)
	)
	(bus
		(pts
			(xy 250.19 205.74) (xy 255.27 205.74)
		)
		(stroke
			(width 0)
			(type default)
		)
	)
	(wire
		(pts
			(xy 295.91 181.61) (xy 295.91 186.69)
		)
		(stroke
			(width 0)
			(type default)
		)
	)
	(wire
		(pts
			(xy 265.43 76.2) (xy 238.76 76.2)
		)
		(stroke
			(width 0)
			(type default)
		)
	)
	(wire
		(pts
			(xy 101.6 173.99) (xy 101.6 176.53)
		)
		(stroke
			(width 0)
			(type default)
		)
	)
	(bus
		(pts
			(xy 266.7 85.09) (xy 266.7 87.63)
		)
		(stroke
			(width 0)
			(type default)
		)
	)
	(wire
		(pts
			(xy 83.82 76.2) (xy 110.49 76.2)
		)
		(stroke
			(width 0)
			(type default)
		)
	)
	(wire
		(pts
			(xy 116.84 196.85) (xy 146.05 196.85)
		)
		(stroke
			(width 0)
			(type default)
		)
	)
	(wire
		(pts
			(xy 83.82 60.96) (xy 83.82 76.2)
		)
		(stroke
			(width 0)
			(type default)
		)
	)
	(wire
		(pts
			(xy 321.31 191.77) (xy 350.52 191.77)
		)
		(stroke
			(width 0)
			(type default)
		)
	)
	(wire
		(pts
			(xy 384.81 88.9) (xy 388.62 88.9)
		)
		(stroke
			(width 0)
			(type default)
		)
	)
	(wire
		(pts
			(xy 54.61 66.04) (xy 92.71 66.04)
		)
		(stroke
			(width 0)
			(type default)
		)
	)
	(bus
		(pts
			(xy 257.81 198.12) (xy 257.81 200.66)
		)
		(stroke
			(width 0)
			(type default)
		)
	)
	(bus
		(pts
			(xy 266.7 72.39) (xy 266.7 77.47)
		)
		(stroke
			(width 0)
			(type default)
		)
	)
	(wire
		(pts
			(xy 265.43 66.04) (xy 238.76 66.04)
		)
		(stroke
			(width 0)
			(type default)
		)
	)
	(wire
		(pts
			(xy 101.6 189.23) (xy 101.6 203.2)
		)
		(stroke
			(width 0)
			(type default)
		)
	)
	(bus
		(pts
			(xy 266.7 69.85) (xy 266.7 72.39)
		)
		(stroke
			(width 0)
			(type default)
		)
	)
	(wire
		(pts
			(xy 379.73 199.39) (xy 378.46 199.39)
		)
		(stroke
			(width 0)
			(type default)
		)
	)
	(bus
		(pts
			(xy 257.81 190.5) (xy 257.81 193.04)
		)
		(stroke
			(width 0)
			(type default)
		)
	)
	(wire
		(pts
			(xy 101.6 87.63) (xy 101.6 88.9)
		)
		(stroke
			(width 0)
			(type default)
		)
	)
	(wire
		(pts
			(xy 115.57 68.58) (xy 146.05 68.58)
		)
		(stroke
			(width 0)
			(type default)
		)
	)
	(wire
		(pts
			(xy 287.02 196.85) (xy 316.23 196.85)
		)
		(stroke
			(width 0)
			(type default)
		)
	)
	(wire
		(pts
			(xy 340.36 78.74) (xy 340.36 88.9)
		)
		(stroke
			(width 0)
			(type default)
		)
	)
	(bus
		(pts
			(xy 266.7 87.63) (xy 266.7 91.44)
		)
		(stroke
			(width 0)
			(type default)
		)
	)
	(wire
		(pts
			(xy 233.68 68.58) (xy 226.06 68.58)
		)
		(stroke
			(width 0)
			(type default)
		)
	)
	(wire
		(pts
			(xy 175.26 199.39) (xy 175.26 200.66)
		)
		(stroke
			(width 0)
			(type default)
		)
	)
	(polyline
		(pts
			(xy 203.2 133.35) (xy 12.7 133.35)
		)
		(stroke
			(width 0)
			(type default)
		)
	)
	(wire
		(pts
			(xy 278.13 173.99) (xy 278.13 176.53)
		)
		(stroke
			(width 0)
			(type default)
		)
	)
	(wire
		(pts
			(xy 54.61 186.69) (xy 92.71 186.69)
		)
		(stroke
			(width 0)
			(type default)
		)
	)
	(wire
		(pts
			(xy 92.71 173.99) (xy 92.71 176.53)
		)
		(stroke
			(width 0)
			(type default)
		)
	)
	(bus
		(pts
			(xy 53.34 193.04) (xy 53.34 195.58)
		)
		(stroke
			(width 0)
			(type default)
		)
	)
	(wire
		(pts
			(xy 116.84 194.31) (xy 146.05 194.31)
		)
		(stroke
			(width 0)
			(type default)
		)
	)
	(wire
		(pts
			(xy 92.71 66.04) (xy 110.49 66.04)
		)
		(stroke
			(width 0)
			(type default)
		)
	)
	(bus
		(pts
			(xy 257.81 200.66) (xy 257.81 203.2)
		)
		(stroke
			(width 0)
			(type default)
		)
	)
	(bus
		(pts
			(xy 53.34 72.39) (xy 53.34 74.93)
		)
		(stroke
			(width 0)
			(type default)
		)
	)
	(wire
		(pts
			(xy 295.91 186.69) (xy 316.23 186.69)
		)
		(stroke
			(width 0)
			(type default)
		)
	)
	(wire
		(pts
			(xy 101.6 181.61) (xy 101.6 189.23)
		)
		(stroke
			(width 0)
			(type default)
		)
	)
	(wire
		(pts
			(xy 396.24 99.06) (xy 392.43 99.06)
		)
		(stroke
			(width 0)
			(type default)
		)
	)
	(polyline
		(pts
			(xy 13.97 127) (xy 203.2 127)
		)
		(stroke
			(width 0)
			(type default)
		)
	)
	(wire
		(pts
			(xy 74.93 173.99) (xy 74.93 176.53)
		)
		(stroke
			(width 0)
			(type default)
		)
	)
	(bus
		(pts
			(xy 240.03 92.71) (xy 265.43 92.71)
		)
		(stroke
			(width 0)
			(type default)
		)
	)
	(wire
		(pts
			(xy 287.02 173.99) (xy 287.02 176.53)
		)
		(stroke
			(width 0)
			(type default)
		)
	)
	(wire
		(pts
			(xy 340.36 49.53) (xy 340.36 73.66)
		)
		(stroke
			(width 0)
			(type default)
		)
	)
	(polyline
		(pts
			(xy 209.55 127) (xy 406.4 127)
		)
		(stroke
			(width 0)
			(type default)
		)
	)
	(wire
		(pts
			(xy 92.71 173.99) (xy 101.6 173.99)
		)
		(stroke
			(width 0)
			(type default)
		)
	)
	(wire
		(pts
			(xy 177.8 78.74) (xy 177.8 80.01)
		)
		(stroke
			(width 0)
			(type default)
		)
	)
	(wire
		(pts
			(xy 173.99 186.69) (xy 177.8 186.69)
		)
		(stroke
			(width 0)
			(type default)
		)
	)
	(wire
		(pts
			(xy 173.99 196.85) (xy 175.26 196.85)
		)
		(stroke
			(width 0)
			(type default)
		)
	)
	(wire
		(pts
			(xy 233.68 71.12) (xy 226.06 71.12)
		)
		(stroke
			(width 0)
			(type default)
		)
	)
	(wire
		(pts
			(xy 115.57 66.04) (xy 146.05 66.04)
		)
		(stroke
			(width 0)
			(type default)
		)
	)
	(wire
		(pts
			(xy 116.84 186.69) (xy 146.05 186.69)
		)
		(stroke
			(width 0)
			(type default)
		)
	)
	(wire
		(pts
			(xy 321.31 199.39) (xy 350.52 199.39)
		)
		(stroke
			(width 0)
			(type default)
		)
	)
	(wire
		(pts
			(xy 278.13 172.72) (xy 278.13 173.99)
		)
		(stroke
			(width 0)
			(type default)
		)
	)
	(wire
		(pts
			(xy 326.39 49.53) (xy 326.39 52.07)
		)
		(stroke
			(width 0)
			(type default)
		)
	)
	(wire
		(pts
			(xy 115.57 71.12) (xy 146.05 71.12)
		)
		(stroke
			(width 0)
			(type default)
		)
	)
	(wire
		(pts
			(xy 115.57 76.2) (xy 146.05 76.2)
		)
		(stroke
			(width 0)
			(type default)
		)
	)
	(wire
		(pts
			(xy 304.8 189.23) (xy 304.8 203.2)
		)
		(stroke
			(width 0)
			(type default)
		)
	)
	(wire
		(pts
			(xy 267.97 86.36) (xy 312.42 86.36)
		)
		(stroke
			(width 0)
			(type default)
		)
	)
	(bus
		(pts
			(xy 53.34 200.66) (xy 53.34 203.2)
		)
		(stroke
			(width 0)
			(type default)
		)
	)
	(wire
		(pts
			(xy 303.53 83.82) (xy 344.17 83.82)
		)
		(stroke
			(width 0)
			(type default)
		)
	)
	(polyline
		(pts
			(xy 203.2 284.48) (xy 203.2 133.35)
		)
		(stroke
			(width 0)
			(type default)
		)
	)
	(wire
		(pts
			(xy 92.71 60.96) (xy 92.71 66.04)
		)
		(stroke
			(width 0)
			(type default)
		)
	)
	(bus
		(pts
			(xy 53.34 195.58) (xy 53.34 198.12)
		)
		(stroke
			(width 0)
			(type default)
		)
	)
	(wire
		(pts
			(xy 379.73 199.39) (xy 379.73 200.66)
		)
		(stroke
			(width 0)
			(type default)
		)
	)
	(bus
		(pts
			(xy 53.34 69.85) (xy 53.34 72.39)
		)
		(stroke
			(width 0)
			(type default)
		)
	)
	(wire
		(pts
			(xy 92.71 186.69) (xy 111.76 186.69)
		)
		(stroke
			(width 0)
			(type default)
		)
	)
	(wire
		(pts
			(xy 226.06 71.12) (xy 226.06 68.58)
		)
		(stroke
			(width 0)
			(type default)
		)
	)
	(wire
		(pts
			(xy 83.82 181.61) (xy 83.82 196.85)
		)
		(stroke
			(width 0)
			(type default)
		)
	)
	(wire
		(pts
			(xy 287.02 173.99) (xy 295.91 173.99)
		)
		(stroke
			(width 0)
			(type default)
		)
	)
	(wire
		(pts
			(xy 54.61 78.74) (xy 74.93 78.74)
		)
		(stroke
			(width 0)
			(type default)
		)
	)
	(wire
		(pts
			(xy 182.88 185.42) (xy 182.88 186.69)
		)
		(stroke
			(width 0)
			(type default)
		)
	)
	(wire
		(pts
			(xy 267.97 68.58) (xy 293.37 68.58)
		)
		(stroke
			(width 0)
			(type default)
		)
	)
	(wire
		(pts
			(xy 267.97 71.12) (xy 293.37 71.12)
		)
		(stroke
			(width 0)
			(type default)
		)
	)
	(wire
		(pts
			(xy 259.08 191.77) (xy 316.23 191.77)
		)
		(stroke
			(width 0)
			(type default)
		)
	)
	(wire
		(pts
			(xy 54.61 71.12) (xy 110.49 71.12)
		)
		(stroke
			(width 0)
			(type default)
		)
	)
	(wire
		(pts
			(xy 177.8 66.04) (xy 177.8 69.85)
		)
		(stroke
			(width 0)
			(type default)
		)
	)
	(wire
		(pts
			(xy 54.61 73.66) (xy 110.49 73.66)
		)
		(stroke
			(width 0)
			(type default)
		)
	)
	(wire
		(pts
			(xy 83.82 173.99) (xy 92.71 173.99)
		)
		(stroke
			(width 0)
			(type default)
		)
	)
	(wire
		(pts
			(xy 265.43 81.28) (xy 238.76 81.28)
		)
		(stroke
			(width 0)
			(type default)
		)
	)
	(wire
		(pts
			(xy 115.57 73.66) (xy 146.05 73.66)
		)
		(stroke
			(width 0)
			(type default)
		)
	)
	(wire
		(pts
			(xy 267.97 66.04) (xy 293.37 66.04)
		)
		(stroke
			(width 0)
			(type default)
		)
	)
	(wire
		(pts
			(xy 116.84 189.23) (xy 146.05 189.23)
		)
		(stroke
			(width 0)
			(type default)
		)
	)
	(wire
		(pts
			(xy 54.61 68.58) (xy 101.6 68.58)
		)
		(stroke
			(width 0)
			(type default)
		)
	)
	(wire
		(pts
			(xy 74.93 181.61) (xy 74.93 199.39)
		)
		(stroke
			(width 0)
			(type default)
		)
	)
	(wire
		(pts
			(xy 54.61 189.23) (xy 101.6 189.23)
		)
		(stroke
			(width 0)
			(type default)
		)
	)
	(wire
		(pts
			(xy 344.17 88.9) (xy 340.36 88.9)
		)
		(stroke
			(width 0)
			(type default)
		)
	)
	(wire
		(pts
			(xy 382.27 199.39) (xy 379.73 199.39)
		)
		(stroke
			(width 0)
			(type default)
		)
	)
	(wire
		(pts
			(xy 74.93 52.07) (xy 74.93 53.34)
		)
		(stroke
			(width 0)
			(type default)
		)
	)
	(wire
		(pts
			(xy 388.62 88.9) (xy 396.24 88.9)
		)
		(stroke
			(width 0)
			(type default)
		)
	)
	(wire
		(pts
			(xy 233.68 81.28) (xy 226.06 81.28)
		)
		(stroke
			(width 0)
			(type default)
		)
	)
	(wire
		(pts
			(xy 54.61 196.85) (xy 83.82 196.85)
		)
		(stroke
			(width 0)
			(type default)
		)
	)
	(bus
		(pts
			(xy 45.72 205.74) (xy 50.8 205.74)
		)
		(stroke
			(width 0)
			(type default)
		)
	)
	(wire
		(pts
			(xy 265.43 86.36) (xy 238.76 86.36)
		)
		(stroke
			(width 0)
			(type default)
		)
	)
	(wire
		(pts
			(xy 382.27 186.69) (xy 391.16 186.69)
		)
		(stroke
			(width 0)
			(type default)
		)
	)
	(wire
		(pts
			(xy 295.91 173.99) (xy 295.91 176.53)
		)
		(stroke
			(width 0)
			(type default)
		)
	)
	(wire
		(pts
			(xy 321.31 186.69) (xy 350.52 186.69)
		)
		(stroke
			(width 0)
			(type default)
		)
	)
	(polyline
		(pts
			(xy 209.55 284.48) (xy 209.55 133.35)
		)
		(stroke
			(width 0)
			(type default)
		)
	)
	(wire
		(pts
			(xy 177.8 66.04) (xy 182.88 66.04)
		)
		(stroke
			(width 0)
			(type default)
		)
	)
	(wire
		(pts
			(xy 226.06 71.12) (xy 226.06 76.2)
		)
		(stroke
			(width 0)
			(type default)
		)
	)
	(wire
		(pts
			(xy 287.02 181.61) (xy 287.02 196.85)
		)
		(stroke
			(width 0)
			(type default)
		)
	)
	(wire
		(pts
			(xy 74.93 78.74) (xy 110.49 78.74)
		)
		(stroke
			(width 0)
			(type default)
		)
	)
	(wire
		(pts
			(xy 54.61 76.2) (xy 83.82 76.2)
		)
		(stroke
			(width 0)
			(type default)
		)
	)
	(wire
		(pts
			(xy 321.31 196.85) (xy 350.52 196.85)
		)
		(stroke
			(width 0)
			(type default)
		)
	)
	(wire
		(pts
			(xy 92.71 181.61) (xy 92.71 186.69)
		)
		(stroke
			(width 0)
			(type default)
		)
	)
	(wire
		(pts
			(xy 259.08 194.31) (xy 316.23 194.31)
		)
		(stroke
			(width 0)
			(type default)
		)
	)
	(wire
		(pts
			(xy 382.27 186.69) (xy 382.27 190.5)
		)
		(stroke
			(width 0)
			(type default)
		)
	)
	(wire
		(pts
			(xy 177.8 74.93) (xy 177.8 78.74)
		)
		(stroke
			(width 0)
			(type default)
		)
	)
	(wire
		(pts
			(xy 326.39 57.15) (xy 326.39 58.42)
		)
		(stroke
			(width 0)
			(type default)
		)
	)
	(wire
		(pts
			(xy 92.71 53.34) (xy 101.6 53.34)
		)
		(stroke
			(width 0)
			(type default)
		)
	)
	(wire
		(pts
			(xy 54.61 194.31) (xy 111.76 194.31)
		)
		(stroke
			(width 0)
			(type default)
		)
	)
	(wire
		(pts
			(xy 304.8 173.99) (xy 304.8 176.53)
		)
		(stroke
			(width 0)
			(type default)
		)
	)
	(wire
		(pts
			(xy 115.57 78.74) (xy 146.05 78.74)
		)
		(stroke
			(width 0)
			(type default)
		)
	)
	(wire
		(pts
			(xy 317.5 86.36) (xy 344.17 86.36)
		)
		(stroke
			(width 0)
			(type default)
		)
	)
	(label "USR_FLASH_0.~{CS}"
		(at 55.88 186.69 0)
		(effects
			(font
				(size 1.27 1.27)
			)
			(justify left bottom)
		)
	)
	(label "SD_CARD.DAT3"
		(at 271.78 68.58 0)
		(effects
			(font
				(size 1.27 1.27)
			)
			(justify left bottom)
		)
	)
	(label "SD_CARD.DAT2"
		(at 247.65 66.04 0)
		(effects
			(font
				(size 1.27 1.27)
			)
			(justify left bottom)
		)
	)
	(label "SD_CARD.CLK"
		(at 247.65 76.2 0)
		(effects
			(font
				(size 1.27 1.27)
			)
			(justify left bottom)
		)
	)
	(label "USR_FLASH_1_DQ1"
		(at 330.2 194.31 0)
		(effects
			(font
				(size 1.27 1.27)
			)
			(justify left bottom)
		)
	)
	(label "USR_FLASH_1.CLK"
		(at 260.35 189.23 0)
		(effects
			(font
				(size 1.27 1.27)
			)
			(justify left bottom)
		)
	)
	(label "SYSTEM_FLASH.DQ2"
		(at 55.88 76.2 0)
		(effects
			(font
				(size 1.27 1.27)
			)
			(justify left bottom)
		)
	)
	(label "USR_FLASH_0.DQ3"
		(at 55.88 199.39 0)
		(effects
			(font
				(size 1.27 1.27)
			)
			(justify left bottom)
		)
	)
	(label "SD_CARD.DAT0"
		(at 247.65 81.28 0)
		(effects
			(font
				(size 1.27 1.27)
			)
			(justify left bottom)
		)
	)
	(label "SD_CARD.DAT1"
		(at 271.78 83.82 0)
		(effects
			(font
				(size 1.27 1.27)
			)
			(justify left bottom)
		)
	)
	(label "SYSTEM_FLASH_DQ1"
		(at 125.73 73.66 0)
		(effects
			(font
				(size 1.27 1.27)
			)
			(justify left bottom)
		)
	)
	(label "SD_CARD.CLK"
		(at 271.78 76.2 0)
		(effects
			(font
				(size 1.27 1.27)
			)
			(justify left bottom)
		)
	)
	(label "USR_FLASH_1.DQ2"
		(at 260.35 196.85 0)
		(effects
			(font
				(size 1.27 1.27)
			)
			(justify left bottom)
		)
	)
	(label "USR_FLASH_0.DQ2"
		(at 55.88 196.85 0)
		(effects
			(font
				(size 1.27 1.27)
			)
			(justify left bottom)
		)
	)
	(label "USR_FLASH_1.DQ0"
		(at 260.35 191.77 0)
		(effects
			(font
				(size 1.27 1.27)
			)
			(justify left bottom)
		)
	)
	(label "SYSTEM_FLASH_DQ2"
		(at 127 76.2 0)
		(effects
			(font
				(size 1.27 1.27)
			)
			(justify left bottom)
		)
	)
	(label "SD_CARD.CMD"
		(at 247.65 71.12 0)
		(effects
			(font
				(size 1.27 1.27)
			)
			(justify left bottom)
		)
	)
	(label "USR_FLASH_0.DQ0"
		(at 55.88 191.77 0)
		(effects
			(font
				(size 1.27 1.27)
			)
			(justify left bottom)
		)
	)
	(label "SYSTEM_FLASH_DQ3"
		(at 125.73 78.74 0)
		(effects
			(font
				(size 1.27 1.27)
			)
			(justify left bottom)
		)
	)
	(label "SD_CARD.DAT0"
		(at 271.78 81.28 0)
		(effects
			(font
				(size 1.27 1.27)
			)
			(justify left bottom)
		)
	)
	(label "SYSTEM_FLASH.CLK"
		(at 55.88 68.58 0)
		(effects
			(font
				(size 1.27 1.27)
			)
			(justify left bottom)
		)
	)
	(label "SD_CARD.DAT1"
		(at 247.65 83.82 0)
		(effects
			(font
				(size 1.27 1.27)
			)
			(justify left bottom)
		)
	)
	(label "USR_FLASH_0_DQ1"
		(at 125.73 194.31 0)
		(effects
			(font
				(size 1.27 1.27)
			)
			(justify left bottom)
		)
	)
	(label "USR_FLASH_0_CLK"
		(at 127 189.23 0)
		(effects
			(font
				(size 1.27 1.27)
			)
			(justify left bottom)
		)
	)
	(label "SD_CARD_~{CD}"
		(at 323.85 86.36 0)
		(effects
			(font
				(size 1.27 1.27)
			)
			(justify left bottom)
		)
	)
	(label "SYSTEM_FLASH.DQ0"
		(at 55.88 71.12 0)
		(effects
			(font
				(size 1.27 1.27)
			)
			(justify left bottom)
		)
	)
	(label "USR_FLASH_1_DQ0"
		(at 331.47 191.77 0)
		(effects
			(font
				(size 1.27 1.27)
			)
			(justify left bottom)
		)
	)
	(label "SYSTEM_FLASH.DQ1"
		(at 55.88 73.66 0)
		(effects
			(font
				(size 1.27 1.27)
			)
			(justify left bottom)
		)
	)
	(label "USR_FLASH_1_~{CS}"
		(at 331.47 186.69 0)
		(effects
			(font
				(size 1.27 1.27)
			)
			(justify left bottom)
		)
	)
	(label "SD_CARD.DAT2"
		(at 271.78 66.04 0)
		(effects
			(font
				(size 1.27 1.27)
			)
			(justify left bottom)
		)
	)
	(label "SD_CARD.DAT3"
		(at 247.65 68.58 0)
		(effects
			(font
				(size 1.27 1.27)
			)
			(justify left bottom)
		)
	)
	(label "USR_FLASH_1.~{CS}"
		(at 260.35 186.69 0)
		(effects
			(font
				(size 1.27 1.27)
			)
			(justify left bottom)
		)
	)
	(label "USR_FLASH_0_~{CS}"
		(at 127 186.69 0)
		(effects
			(font
				(size 1.27 1.27)
			)
			(justify left bottom)
		)
	)
	(label "SD_CARD.~{CD}"
		(at 247.65 86.36 0)
		(effects
			(font
				(size 1.27 1.27)
			)
			(justify left bottom)
		)
	)
	(label "USR_FLASH_1.DQ1"
		(at 260.35 194.31 0)
		(effects
			(font
				(size 1.27 1.27)
			)
			(justify left bottom)
		)
	)
	(label "USR_FLASH_0_DQ0"
		(at 127 191.77 0)
		(effects
			(font
				(size 1.27 1.27)
			)
			(justify left bottom)
		)
	)
	(label "USR_FLASH_1.DQ3"
		(at 260.35 199.39 0)
		(effects
			(font
				(size 1.27 1.27)
			)
			(justify left bottom)
		)
	)
	(label "USR_FLASH_0.CLK"
		(at 55.88 189.23 0)
		(effects
			(font
				(size 1.27 1.27)
			)
			(justify left bottom)
		)
	)
	(label "SYSTEM_FLASH_CLK"
		(at 127 68.58 0)
		(effects
			(font
				(size 1.27 1.27)
			)
			(justify left bottom)
		)
	)
	(label "USR_FLASH_1_DQ3"
		(at 330.2 199.39 0)
		(effects
			(font
				(size 1.27 1.27)
			)
			(justify left bottom)
		)
	)
	(label "USR_FLASH_1_CLK"
		(at 331.47 189.23 0)
		(effects
			(font
				(size 1.27 1.27)
			)
			(justify left bottom)
		)
	)
	(label "SYSTEM_FLASH.~{CS}"
		(at 55.88 66.04 0)
		(effects
			(font
				(size 1.27 1.27)
			)
			(justify left bottom)
		)
	)
	(label "SYSTEM_FLASH.DQ3"
		(at 55.88 78.74 0)
		(effects
			(font
				(size 1.27 1.27)
			)
			(justify left bottom)
		)
	)
	(label "USR_FLASH_0_DQ3"
		(at 125.73 199.39 0)
		(effects
			(font
				(size 1.27 1.27)
			)
			(justify left bottom)
		)
	)
	(label "SD_CARD.CMD"
		(at 271.78 71.12 0)
		(effects
			(font
				(size 1.27 1.27)
			)
			(justify left bottom)
		)
	)
	(label "SYSTEM_FLASH_~{CS}"
		(at 127 66.04 0)
		(effects
			(font
				(size 1.27 1.27)
			)
			(justify left bottom)
		)
	)
	(label "USR_FLASH_0.DQ1"
		(at 55.88 194.31 0)
		(effects
			(font
				(size 1.27 1.27)
			)
			(justify left bottom)
		)
	)
	(label "SD_CARD.~{CD}"
		(at 271.78 86.36 0)
		(effects
			(font
				(size 1.27 1.27)
			)
			(justify left bottom)
		)
	)
	(label "USR_FLASH_0_DQ2"
		(at 127 196.85 0)
		(effects
			(font
				(size 1.27 1.27)
			)
			(justify left bottom)
		)
	)
	(label "USR_FLASH_1_DQ2"
		(at 331.47 196.85 0)
		(effects
			(font
				(size 1.27 1.27)
			)
			(justify left bottom)
		)
	)
	(label "SYSTEM_FLASH_DQ0"
		(at 127 71.12 0)
		(effects
			(font
				(size 1.27 1.27)
			)
			(justify left bottom)
		)
	)
	(hierarchical_label "SD_CARD{SD-CARD}"
		(shape bidirectional)
		(at 240.03 92.71 180)
		(effects
			(font
				(size 1.27 1.27)
			)
			(justify right)
		)
	)
	(hierarchical_label "USR_FLASH_0{SPI-FLASH}"
		(shape bidirectional)
		(at 45.72 205.74 180)
		(effects
			(font
				(size 1.27 1.27)
			)
			(justify right)
		)
	)
	(hierarchical_label "SYSTEM_FLASH{SPI-FLASH}"
		(shape bidirectional)
		(at 45.72 85.09 180)
		(effects
			(font
				(size 1.27 1.27)
			)
			(justify right)
		)
	)
	(hierarchical_label "USR_FLASH_1{SPI-FLASH}"
		(shape bidirectional)
		(at 250.19 205.74 180)
		(effects
			(font
				(size 1.27 1.27)
			)
			(justify right)
		)
	)
	(symbol
		(lib_id "antmicropower:+3.3V")
		(at 74.93 52.07 0)
		(unit 1)
		(exclude_from_sim no)
		(in_bom yes)
		(on_board yes)
		(dnp no)
		(fields_autoplaced yes)
		(property "Reference" "#PWR0114"
			(at 74.93 55.88 0)
			(effects
				(font
					(size 1.27 1.27)
				)
				(hide yes)
			)
		)
		(property "Value" "+3V3"
			(at 74.93 48.514 0)
			(effects
				(font
					(size 1.27 1.27)
				)
			)
		)
		(property "Footprint" ""
			(at 74.93 52.07 0)
			(effects
				(font
					(size 1.27 1.27)
				)
				(hide yes)
			)
		)
		(property "Datasheet" ""
			(at 74.93 52.07 0)
			(effects
				(font
					(size 1.27 1.27)
				)
				(hide yes)
			)
		)
		(property "Description" ""
			(at 74.93 52.07 0)
			(effects
				(font
					(size 1.27 1.27)
				)
			)
		)
		(pin "1"
		)
		(instances
			(project "k410t-devboard"
				(path ""
					(reference "#PWR0114")
					(unit 1)
				)
			)
		)
	)
	(symbol
		(lib_id "antmicroResistors0402:R_100R_0402")
		(at 101.6 87.63 90)
		(unit 1)
		(exclude_from_sim no)
		(in_bom no)
		(on_board yes)
		(dnp yes)
		(property "Reference" "R71"
			(at 102.87 83.82 90)
			(effects
				(font
					(size 1.27 1.27)
				)
				(justify right)
			)
		)
		(property "Value" "R_100R_0402"
			(at 114.3 67.31 0)
			(effects
				(font
					(size 1.27 1.27)
					(thickness 0.15)
				)
				(justify left bottom)
				(hide yes)
			)
		)
		(property "Footprint" "antmicro-footprints:R_0402_1005Metric"
			(at 116.84 67.31 0)
			(effects
				(font
					(size 1.27 1.27)
					(thickness 0.15)
				)
				(justify left bottom)
				(hide yes)
			)
		)
		(property "Datasheet" "https://www.bourns.com/docs/product-datasheets/cr.pdf"
			(at 119.38 67.31 0)
			(effects
				(font
					(size 1.27 1.27)
					(thickness 0.15)
				)
				(justify left bottom)
				(hide yes)
			)
		)
		(property "Description" ""
			(at 101.6 87.63 0)
			(effects
				(font
					(size 1.27 1.27)
				)
			)
		)
		(property "Manufacturer" "Bourns"
			(at 124.46 67.31 0)
			(effects
				(font
					(size 1.27 1.27)
					(thickness 0.15)
				)
				(justify left bottom)
				(hide yes)
			)
		)
		(property "MPN" "CR0402-FX-1000GLF"
			(at 121.92 67.31 0)
			(effects
				(font
					(size 1.27 1.27)
					(thickness 0.15)
				)
				(justify left bottom)
				(hide yes)
			)
		)
		(property "Val" "100R"
			(at 102.87 86.36 90)
			(effects
				(font
					(size 1.27 1.27)
					(thickness 0.15)
				)
				(justify right)
			)
		)
		(property "DNP" "DNP"
			(at 101.6 83.185 0)
			(effects
				(font
					(size 1.27 1.27)
				)
				(justify right)
			)
		)
		(property "License" "Apache-2.0"
			(at 127 67.31 0)
			(effects
				(font
					(size 1.27 1.27)
					(thickness 0.15)
				)
				(justify left bottom)
				(hide yes)
			)
		)
		(property "Author" "Antmicro"
			(at 129.54 67.31 0)
			(effects
				(font
					(size 1.27 1.27)
					(thickness 0.15)
				)
				(justify left bottom)
				(hide yes)
			)
		)
		(property "Tolerance" "1%"
			(at 111.76 67.31 0)
			(effects
				(font
					(size 1.27 1.27)
				)
				(justify left bottom)
				(hide yes)
			)
		)
		(pin "1"
		)
		(pin "2"
		)
		(instances
			(project "k410t-devboard"
				(path ""
					(reference "R71")
					(unit 1)
				)
			)
		)
	)
	(symbol
		(lib_id "antmicroResistors0402:R_0R_0402")
		(at 111.76 186.69 0)
		(unit 1)
		(exclude_from_sim no)
		(in_bom yes)
		(on_board yes)
		(dnp no)
		(property "Reference" "R80"
			(at 118.745 185.42 0)
			(effects
				(font
					(size 1.27 1.27)
				)
			)
		)
		(property "Value" "R_0R_0402"
			(at 132.08 199.39 0)
			(effects
				(font
					(size 1.27 1.27)
					(thickness 0.15)
				)
				(justify left bottom)
				(hide yes)
			)
		)
		(property "Footprint" "antmicro-footprints:R_0402_1005Metric"
			(at 132.08 201.93 0)
			(effects
				(font
					(size 1.27 1.27)
					(thickness 0.15)
				)
				(justify left bottom)
				(hide yes)
			)
		)
		(property "Datasheet" "https://industrial.panasonic.com/cdbs/www-data/pdf/RDA0000/AOA0000C301.pdf"
			(at 132.08 204.47 0)
			(effects
				(font
					(size 1.27 1.27)
					(thickness 0.15)
				)
				(justify left bottom)
				(hide yes)
			)
		)
		(property "Description" ""
			(at 111.76 186.69 0)
			(effects
				(font
					(size 1.27 1.27)
				)
			)
		)
		(property "Manufacturer" "Panasonic"
			(at 132.08 209.55 0)
			(effects
				(font
					(size 1.27 1.27)
					(thickness 0.15)
				)
				(justify left bottom)
				(hide yes)
			)
		)
		(property "MPN" "ERJ2GE0R00X"
			(at 132.08 207.01 0)
			(effects
				(font
					(size 1.27 1.27)
					(thickness 0.15)
				)
				(justify left bottom)
				(hide yes)
			)
		)
		(property "Val" "0R"
			(at 110.49 185.42 0)
			(effects
				(font
					(size 1.27 1.27)
					(thickness 0.15)
				)
			)
		)
		(property "License" "Apache-2.0"
			(at 132.08 212.09 0)
			(effects
				(font
					(size 1.27 1.27)
					(thickness 0.15)
				)
				(justify left bottom)
				(hide yes)
			)
		)
		(property "Author" "Antmicro"
			(at 132.08 214.63 0)
			(effects
				(font
					(size 1.27 1.27)
					(thickness 0.15)
				)
				(justify left bottom)
				(hide yes)
			)
		)
		(property "Tolerance" "~"
			(at 132.08 196.85 0)
			(effects
				(font
					(size 1.27 1.27)
				)
				(justify left bottom)
				(hide yes)
			)
		)
		(property "Current" "1A"
			(at 132.08 217.17 0)
			(effects
				(font
					(size 1.27 1.27)
					(thickness 0.15)
				)
				(justify left bottom)
				(hide yes)
			)
		)
		(pin "1"
		)
		(pin "2"
		)
		(instances
			(project "k410t-devboard"
				(path ""
					(reference "R80")
					(unit 1)
				)
			)
		)
	)
	(symbol
		(lib_id "antmicropower:GND")
		(at 326.39 58.42 0)
		(unit 1)
		(exclude_from_sim no)
		(in_bom yes)
		(on_board yes)
		(dnp no)
		(property "Reference" "#PWR0127"
			(at 326.39 64.77 0)
			(effects
				(font
					(size 1.27 1.27)
				)
				(hide yes)
			)
		)
		(property "Value" "GND"
			(at 326.39 62.23 0)
			(effects
				(font
					(size 1.27 1.27)
				)
			)
		)
		(property "Footprint" ""
			(at 335.28 66.04 0)
			(effects
				(font
					(size 1.27 1.27)
					(thickness 0.15)
				)
				(justify left bottom)
				(hide yes)
			)
		)
		(property "Datasheet" ""
			(at 335.28 71.12 0)
			(effects
				(font
					(size 1.27 1.27)
					(thickness 0.15)
				)
				(justify left bottom)
				(hide yes)
			)
		)
		(property "Description" ""
			(at 326.39 58.42 0)
			(effects
				(font
					(size 1.27 1.27)
				)
			)
		)
		(property "Author" "Antmicro"
			(at 335.28 66.04 0)
			(effects
				(font
					(size 1.27 1.27)
					(thickness 0.15)
				)
				(justify left bottom)
				(hide yes)
			)
		)
		(property "License" "Apache-2.0"
			(at 335.28 68.58 0)
			(effects
				(font
					(size 1.27 1.27)
					(thickness 0.15)
				)
				(justify left bottom)
				(hide yes)
			)
		)
		(pin "1"
		)
		(instances
			(project "k410t-devboard"
				(path ""
					(reference "#PWR0127")
					(unit 1)
				)
			)
		)
	)
	(symbol
		(lib_id "antmicroResistors0402:R_0R_0402")
		(at 110.49 68.58 0)
		(unit 1)
		(exclude_from_sim no)
		(in_bom yes)
		(on_board yes)
		(dnp no)
		(property "Reference" "R75"
			(at 117.475 67.31 0)
			(effects
				(font
					(size 1.27 1.27)
				)
			)
		)
		(property "Value" "R_0R_0402"
			(at 130.81 81.28 0)
			(effects
				(font
					(size 1.27 1.27)
					(thickness 0.15)
				)
				(justify left bottom)
				(hide yes)
			)
		)
		(property "Footprint" "antmicro-footprints:R_0402_1005Metric"
			(at 130.81 83.82 0)
			(effects
				(font
					(size 1.27 1.27)
					(thickness 0.15)
				)
				(justify left bottom)
				(hide yes)
			)
		)
		(property "Datasheet" "https://industrial.panasonic.com/cdbs/www-data/pdf/RDA0000/AOA0000C301.pdf"
			(at 130.81 86.36 0)
			(effects
				(font
					(size 1.27 1.27)
					(thickness 0.15)
				)
				(justify left bottom)
				(hide yes)
			)
		)
		(property "Description" ""
			(at 110.49 68.58 0)
			(effects
				(font
					(size 1.27 1.27)
				)
			)
		)
		(property "Manufacturer" "Panasonic"
			(at 130.81 91.44 0)
			(effects
				(font
					(size 1.27 1.27)
					(thickness 0.15)
				)
				(justify left bottom)
				(hide yes)
			)
		)
		(property "MPN" "ERJ2GE0R00X"
			(at 130.81 88.9 0)
			(effects
				(font
					(size 1.27 1.27)
					(thickness 0.15)
				)
				(justify left bottom)
				(hide yes)
			)
		)
		(property "Val" "0R"
			(at 109.22 67.31 0)
			(effects
				(font
					(size 1.27 1.27)
					(thickness 0.15)
				)
			)
		)
		(property "License" "Apache-2.0"
			(at 130.81 93.98 0)
			(effects
				(font
					(size 1.27 1.27)
					(thickness 0.15)
				)
				(justify left bottom)
				(hide yes)
			)
		)
		(property "Author" "Antmicro"
			(at 130.81 96.52 0)
			(effects
				(font
					(size 1.27 1.27)
					(thickness 0.15)
				)
				(justify left bottom)
				(hide yes)
			)
		)
		(property "Tolerance" "~"
			(at 130.81 78.74 0)
			(effects
				(font
					(size 1.27 1.27)
				)
				(justify left bottom)
				(hide yes)
			)
		)
		(property "Current" "1A"
			(at 130.81 99.06 0)
			(effects
				(font
					(size 1.27 1.27)
					(thickness 0.15)
				)
				(justify left bottom)
				(hide yes)
			)
		)
		(pin "1"
		)
		(pin "2"
		)
		(instances
			(project "k410t-devboard"
				(path ""
					(reference "R75")
					(unit 1)
				)
			)
		)
	)
	(symbol
		(lib_id "antmicroCapacitors0402:C_100n_0402")
		(at 177.8 195.58 90)
		(unit 1)
		(exclude_from_sim no)
		(in_bom yes)
		(on_board yes)
		(dnp no)
		(fields_autoplaced yes)
		(property "Reference" "C210"
			(at 180.34 191.7635 90)
			(effects
				(font
					(size 1.27 1.27)
				)
				(justify right)
			)
		)
		(property "Value" "C_100n_0402"
			(at 187.96 175.26 0)
			(effects
				(font
					(size 1.27 1.27)
					(thickness 0.15)
				)
				(justify left bottom)
				(hide yes)
			)
		)
		(property "Footprint" "antmicro-footprints:C_0402_1005Metric"
			(at 190.5 175.26 0)
			(effects
				(font
					(size 1.27 1.27)
					(thickness 0.15)
				)
				(justify left bottom)
				(hide yes)
			)
		)
		(property "Datasheet" "https://www.murata.com/products/productdetail?partno=GRM155R61H104KE14%23"
			(at 193.04 175.26 0)
			(effects
				(font
					(size 1.27 1.27)
					(thickness 0.15)
				)
				(justify left bottom)
				(hide yes)
			)
		)
		(property "Description" ""
			(at 177.8 195.58 0)
			(effects
				(font
					(size 1.27 1.27)
				)
			)
		)
		(property "Manufacturer" "Murata"
			(at 198.12 175.26 0)
			(effects
				(font
					(size 1.27 1.27)
					(thickness 0.15)
				)
				(justify left bottom)
				(hide yes)
			)
		)
		(property "MPN" "GRM155R61H104KE14D"
			(at 195.58 175.26 0)
			(effects
				(font
					(size 1.27 1.27)
					(thickness 0.15)
				)
				(justify left bottom)
				(hide yes)
			)
		)
		(property "Val" "100n"
			(at 180.34 194.3035 90)
			(effects
				(font
					(size 1.27 1.27)
					(thickness 0.15)
				)
				(justify right)
			)
		)
		(property "License" "Apache-2.0"
			(at 200.66 175.26 0)
			(effects
				(font
					(size 1.27 1.27)
					(thickness 0.15)
				)
				(justify left bottom)
				(hide yes)
			)
		)
		(property "Author" "Antmicro"
			(at 203.2 175.26 0)
			(effects
				(font
					(size 1.27 1.27)
					(thickness 0.15)
				)
				(justify left bottom)
				(hide yes)
			)
		)
		(property "Voltage" "50V"
			(at 205.74 175.26 0)
			(effects
				(font
					(size 1.27 1.27)
				)
				(justify left bottom)
				(hide yes)
			)
		)
		(property "Dielectric" "X5R"
			(at 208.28 175.26 0)
			(effects
				(font
					(size 1.27 1.27)
				)
				(justify left bottom)
				(hide yes)
			)
		)
		(pin "1"
		)
		(pin "2"
		)
		(instances
			(project "k410t-devboard"
				(path ""
					(reference "C210")
					(unit 1)
				)
			)
		)
	)
	(symbol
		(lib_id "antmicroResistors0402:R_10k_0402")
		(at 295.91 181.61 90)
		(unit 1)
		(exclude_from_sim no)
		(in_bom yes)
		(on_board yes)
		(dnp no)
		(property "Reference" "R95"
			(at 297.18 177.8 90)
			(effects
				(font
					(size 1.27 1.27)
				)
				(justify right)
			)
		)
		(property "Value" "R_10k_0402"
			(at 308.61 161.29 0)
			(effects
				(font
					(size 1.27 1.27)
					(thickness 0.15)
				)
				(justify left bottom)
				(hide yes)
			)
		)
		(property "Footprint" "antmicro-footprints:R_0402_1005Metric"
			(at 311.15 161.29 0)
			(effects
				(font
					(size 1.27 1.27)
					(thickness 0.15)
				)
				(justify left bottom)
				(hide yes)
			)
		)
		(property "Datasheet" "https://www.bourns.com/docs/product-datasheets/cr.pdf"
			(at 313.69 161.29 0)
			(effects
				(font
					(size 1.27 1.27)
					(thickness 0.15)
				)
				(justify left bottom)
				(hide yes)
			)
		)
		(property "Description" ""
			(at 295.91 181.61 0)
			(effects
				(font
					(size 1.27 1.27)
				)
			)
		)
		(property "Manufacturer" "Bourns"
			(at 318.77 161.29 0)
			(effects
				(font
					(size 1.27 1.27)
					(thickness 0.15)
				)
				(justify left bottom)
				(hide yes)
			)
		)
		(property "MPN" "CR0402-FX-1002GLF"
			(at 316.23 161.29 0)
			(effects
				(font
					(size 1.27 1.27)
					(thickness 0.15)
				)
				(justify left bottom)
				(hide yes)
			)
		)
		(property "Val" "10k"
			(at 297.18 180.34 90)
			(effects
				(font
					(size 1.27 1.27)
					(thickness 0.15)
				)
				(justify right)
			)
		)
		(property "License" "Apache-2.0"
			(at 321.31 161.29 0)
			(effects
				(font
					(size 1.27 1.27)
					(thickness 0.15)
				)
				(justify left bottom)
				(hide yes)
			)
		)
		(property "Author" "Antmicro"
			(at 323.85 161.29 0)
			(effects
				(font
					(size 1.27 1.27)
					(thickness 0.15)
				)
				(justify left bottom)
				(hide yes)
			)
		)
		(property "Tolerance" "1%"
			(at 306.07 161.29 0)
			(effects
				(font
					(size 1.27 1.27)
				)
				(justify left bottom)
				(hide yes)
			)
		)
		(pin "1"
		)
		(pin "2"
		)
		(instances
			(project "k410t-devboard"
				(path ""
					(reference "R95")
					(unit 1)
				)
			)
		)
	)
	(symbol
		(lib_id "antmicroCapacitors0402:C_100n_0402")
		(at 388.62 96.52 90)
		(unit 1)
		(exclude_from_sim no)
		(in_bom yes)
		(on_board yes)
		(dnp no)
		(property "Reference" "C393"
			(at 389.255 92.075 90)
			(effects
				(font
					(size 1.27 1.27)
				)
				(justify right)
			)
		)
		(property "Value" "C_100n_0402"
			(at 398.78 76.2 0)
			(effects
				(font
					(size 1.27 1.27)
					(thickness 0.15)
				)
				(justify left bottom)
				(hide yes)
			)
		)
		(property "Footprint" "antmicro-footprints:C_0402_1005Metric"
			(at 401.32 76.2 0)
			(effects
				(font
					(size 1.27 1.27)
					(thickness 0.15)
				)
				(justify left bottom)
				(hide yes)
			)
		)
		(property "Datasheet" "https://www.murata.com/products/productdetail?partno=GRM155R61H104KE14%23"
			(at 403.86 76.2 0)
			(effects
				(font
					(size 1.27 1.27)
					(thickness 0.15)
				)
				(justify left bottom)
				(hide yes)
			)
		)
		(property "Description" ""
			(at 388.62 96.52 0)
			(effects
				(font
					(size 1.27 1.27)
				)
			)
		)
		(property "Manufacturer" "Murata"
			(at 408.94 76.2 0)
			(effects
				(font
					(size 1.27 1.27)
					(thickness 0.15)
				)
				(justify left bottom)
				(hide yes)
			)
		)
		(property "MPN" "GRM155R61H104KE14D"
			(at 406.4 76.2 0)
			(effects
				(font
					(size 1.27 1.27)
					(thickness 0.15)
				)
				(justify left bottom)
				(hide yes)
			)
		)
		(property "Val" "100n"
			(at 389.255 95.885 90)
			(effects
				(font
					(size 1.27 1.27)
					(thickness 0.15)
				)
				(justify right)
			)
		)
		(property "License" "Apache-2.0"
			(at 411.48 76.2 0)
			(effects
				(font
					(size 1.27 1.27)
					(thickness 0.15)
				)
				(justify left bottom)
				(hide yes)
			)
		)
		(property "Author" "Antmicro"
			(at 414.02 76.2 0)
			(effects
				(font
					(size 1.27 1.27)
					(thickness 0.15)
				)
				(justify left bottom)
				(hide yes)
			)
		)
		(property "Voltage" "50V"
			(at 416.56 76.2 0)
			(effects
				(font
					(size 1.27 1.27)
				)
				(justify left bottom)
				(hide yes)
			)
		)
		(property "Dielectric" "X5R"
			(at 419.1 76.2 0)
			(effects
				(font
					(size 1.27 1.27)
				)
				(justify left bottom)
				(hide yes)
			)
		)
		(pin "1"
		)
		(pin "2"
		)
		(instances
			(project "k410t-devboard"
				(path ""
					(reference "C393")
					(unit 1)
				)
			)
		)
	)
	(symbol
		(lib_id "antmicroResistors0402:R_0R_0402")
		(at 111.76 199.39 0)
		(unit 1)
		(exclude_from_sim no)
		(in_bom yes)
		(on_board yes)
		(dnp no)
		(property "Reference" "R85"
			(at 118.745 198.12 0)
			(effects
				(font
					(size 1.27 1.27)
				)
			)
		)
		(property "Value" "R_0R_0402"
			(at 132.08 212.09 0)
			(effects
				(font
					(size 1.27 1.27)
					(thickness 0.15)
				)
				(justify left bottom)
				(hide yes)
			)
		)
		(property "Footprint" "antmicro-footprints:R_0402_1005Metric"
			(at 132.08 214.63 0)
			(effects
				(font
					(size 1.27 1.27)
					(thickness 0.15)
				)
				(justify left bottom)
				(hide yes)
			)
		)
		(property "Datasheet" "https://industrial.panasonic.com/cdbs/www-data/pdf/RDA0000/AOA0000C301.pdf"
			(at 132.08 217.17 0)
			(effects
				(font
					(size 1.27 1.27)
					(thickness 0.15)
				)
				(justify left bottom)
				(hide yes)
			)
		)
		(property "Description" ""
			(at 111.76 199.39 0)
			(effects
				(font
					(size 1.27 1.27)
				)
			)
		)
		(property "Manufacturer" "Panasonic"
			(at 132.08 222.25 0)
			(effects
				(font
					(size 1.27 1.27)
					(thickness 0.15)
				)
				(justify left bottom)
				(hide yes)
			)
		)
		(property "MPN" "ERJ2GE0R00X"
			(at 132.08 219.71 0)
			(effects
				(font
					(size 1.27 1.27)
					(thickness 0.15)
				)
				(justify left bottom)
				(hide yes)
			)
		)
		(property "Val" "0R"
			(at 110.49 198.12 0)
			(effects
				(font
					(size 1.27 1.27)
					(thickness 0.15)
				)
			)
		)
		(property "License" "Apache-2.0"
			(at 132.08 224.79 0)
			(effects
				(font
					(size 1.27 1.27)
					(thickness 0.15)
				)
				(justify left bottom)
				(hide yes)
			)
		)
		(property "Author" "Antmicro"
			(at 132.08 227.33 0)
			(effects
				(font
					(size 1.27 1.27)
					(thickness 0.15)
				)
				(justify left bottom)
				(hide yes)
			)
		)
		(property "Tolerance" "~"
			(at 132.08 209.55 0)
			(effects
				(font
					(size 1.27 1.27)
				)
				(justify left bottom)
				(hide yes)
			)
		)
		(property "Current" "1A"
			(at 132.08 229.87 0)
			(effects
				(font
					(size 1.27 1.27)
					(thickness 0.15)
				)
				(justify left bottom)
				(hide yes)
			)
		)
		(pin "1"
		)
		(pin "2"
		)
		(instances
			(project "k410t-devboard"
				(path ""
					(reference "R85")
					(unit 1)
				)
			)
		)
	)
	(symbol
		(lib_id "antmicroCapacitors0402:C_1u_0402")
		(at 326.39 57.15 90)
		(unit 1)
		(exclude_from_sim no)
		(in_bom yes)
		(on_board yes)
		(dnp no)
		(fields_autoplaced yes)
		(property "Reference" "C211"
			(at 328.93 53.3335 90)
			(effects
				(font
					(size 1.27 1.27)
				)
				(justify right)
			)
		)
		(property "Value" "C_1u_0402"
			(at 336.55 36.83 0)
			(effects
				(font
					(size 1.27 1.27)
					(thickness 0.15)
				)
				(justify left bottom)
				(hide yes)
			)
		)
		(property "Footprint" "antmicro-footprints:C_0402_1005Metric"
			(at 339.09 36.83 0)
			(effects
				(font
					(size 1.27 1.27)
					(thickness 0.15)
				)
				(justify left bottom)
				(hide yes)
			)
		)
		(property "Datasheet" "https://product.tdk.com/en/search/capacitor/ceramic/mlcc/info?part_no=C1005X6S1A105K050BC"
			(at 341.63 36.83 0)
			(effects
				(font
					(size 1.27 1.27)
					(thickness 0.15)
				)
				(justify left bottom)
				(hide yes)
			)
		)
		(property "Description" ""
			(at 326.39 57.15 0)
			(effects
				(font
					(size 1.27 1.27)
				)
			)
		)
		(property "Manufacturer" "TDK"
			(at 346.71 36.83 0)
			(effects
				(font
					(size 1.27 1.27)
					(thickness 0.15)
				)
				(justify left bottom)
				(hide yes)
			)
		)
		(property "MPN" "C1005X6S1A105K050BC"
			(at 344.17 36.83 0)
			(effects
				(font
					(size 1.27 1.27)
					(thickness 0.15)
				)
				(justify left bottom)
				(hide yes)
			)
		)
		(property "Val" "1u"
			(at 328.93 55.8735 90)
			(effects
				(font
					(size 1.27 1.27)
					(thickness 0.15)
				)
				(justify right)
			)
		)
		(property "License" "Apache-2.0"
			(at 349.25 36.83 0)
			(effects
				(font
					(size 1.27 1.27)
					(thickness 0.15)
				)
				(justify left bottom)
				(hide yes)
			)
		)
		(property "Author" "Antmicro"
			(at 351.79 36.83 0)
			(effects
				(font
					(size 1.27 1.27)
					(thickness 0.15)
				)
				(justify left bottom)
				(hide yes)
			)
		)
		(property "Voltage" ""
			(at 354.33 36.83 0)
			(effects
				(font
					(size 1.27 1.27)
				)
				(justify left bottom)
				(hide yes)
			)
		)
		(property "Dielectric" ""
			(at 356.87 36.83 0)
			(effects
				(font
					(size 1.27 1.27)
				)
				(justify left bottom)
				(hide yes)
			)
		)
		(pin "1"
		)
		(pin "2"
		)
		(instances
			(project "k410t-devboard"
				(path ""
					(reference "C211")
					(unit 1)
				)
			)
		)
	)
	(symbol
		(lib_id "antmicroMemory:MT25QL256ABA1EW7-0SIT")
		(at 146.05 66.04 0)
		(unit 1)
		(exclude_from_sim no)
		(in_bom yes)
		(on_board yes)
		(dnp no)
		(fields_autoplaced yes)
		(property "Reference" "U12"
			(at 160.02 58.42 0)
			(effects
				(font
					(size 1.27 1.27)
				)
			)
		)
		(property "Value" "MT25QL256ABA1EW7-0SIT"
			(at 160.02 60.96 0)
			(effects
				(font
					(size 1.27 1.27)
					(thickness 0.15)
				)
				(hide yes)
			)
		)
		(property "Footprint" "antmicro-footprints:WDFN-8-1EP_6x5mm_P1.27mm_EP3.4x4mm"
			(at 187.96 73.66 0)
			(effects
				(font
					(size 1.27 1.27)
					(thickness 0.15)
				)
				(justify left bottom)
				(hide yes)
			)
		)
		(property "Datasheet" "https://www.micron.com/products/nor-flash/serial-nor-flash/part-catalog/mt25ql256aba1ew7-0sit"
			(at 187.96 76.2 0)
			(effects
				(font
					(size 1.27 1.27)
					(thickness 0.15)
				)
				(justify left bottom)
				(hide yes)
			)
		)
		(property "Description" ""
			(at 146.05 66.04 0)
			(effects
				(font
					(size 1.27 1.27)
				)
			)
		)
		(property "MPN" "MT25QL256ABA1EW7-0SIT"
			(at 160.02 60.96 0)
			(effects
				(font
					(size 1.27 1.27)
					(thickness 0.15)
				)
			)
		)
		(property "Manufacturer" "Micron Technology"
			(at 187.96 81.28 0)
			(effects
				(font
					(size 1.27 1.27)
					(thickness 0.15)
				)
				(justify left bottom)
				(hide yes)
			)
		)
		(property "Author" "Antmicro"
			(at 187.96 83.82 0)
			(effects
				(font
					(size 1.27 1.27)
					(thickness 0.15)
				)
				(justify left bottom)
				(hide yes)
			)
		)
		(property "License" "Apache-2.0"
			(at 187.96 86.36 0)
			(effects
				(font
					(size 1.27 1.27)
					(thickness 0.15)
				)
				(justify left bottom)
				(hide yes)
			)
		)
		(pin "1"
		)
		(pin "2"
		)
		(pin "3"
		)
		(pin "4"
		)
		(pin "5"
		)
		(pin "6"
		)
		(pin "7"
		)
		(pin "8"
		)
		(pin "9"
		)
		(instances
			(project "k410t-devboard"
				(path ""
					(reference "U12")
					(unit 1)
				)
			)
		)
	)
	(symbol
		(lib_id "antmicropower:+1V8")
		(at 182.88 185.42 0)
		(unit 1)
		(exclude_from_sim no)
		(in_bom yes)
		(on_board yes)
		(dnp no)
		(fields_autoplaced yes)
		(property "Reference" "#PWR0121"
			(at 182.88 189.23 0)
			(effects
				(font
					(size 1.27 1.27)
				)
				(hide yes)
			)
		)
		(property "Value" "+1V8"
			(at 182.88 181.864 0)
			(effects
				(font
					(size 1.27 1.27)
				)
			)
		)
		(property "Footprint" ""
			(at 198.12 193.04 0)
			(effects
				(font
					(size 1.27 1.27)
					(thickness 0.15)
				)
				(justify left bottom)
				(hide yes)
			)
		)
		(property "Datasheet" ""
			(at 198.12 195.58 0)
			(effects
				(font
					(size 1.27 1.27)
					(thickness 0.15)
				)
				(justify left bottom)
				(hide yes)
			)
		)
		(property "Description" ""
			(at 182.88 185.42 0)
			(effects
				(font
					(size 1.27 1.27)
				)
			)
		)
		(property "Author" "Antmicro"
			(at 198.12 193.04 0)
			(effects
				(font
					(size 1.27 1.27)
					(thickness 0.15)
				)
				(justify left bottom)
				(hide yes)
			)
		)
		(property "License" "Apache-2.0"
			(at 198.12 195.58 0)
			(effects
				(font
					(size 1.27 1.27)
					(thickness 0.15)
				)
				(justify left bottom)
				(hide yes)
			)
		)
		(pin "1"
		)
		(instances
			(project "k410t-devboard"
				(path ""
					(reference "#PWR0121")
					(unit 1)
				)
			)
		)
	)
	(symbol
		(lib_id "antmicropower:VCC_USR_B")
		(at 391.16 185.42 0)
		(mirror y)
		(unit 1)
		(exclude_from_sim no)
		(in_bom yes)
		(on_board yes)
		(dnp no)
		(fields_autoplaced yes)
		(property "Reference" "#PWR0442"
			(at 391.16 189.23 0)
			(effects
				(font
					(size 1.27 1.27)
				)
				(hide yes)
			)
		)
		(property "Value" "VCC_USR_B"
			(at 391.16 181.61 0)
			(effects
				(font
					(size 1.27 1.27)
				)
			)
		)
		(property "Footprint" ""
			(at 391.16 185.42 0)
			(effects
				(font
					(size 1.27 1.27)
				)
				(hide yes)
			)
		)
		(property "Datasheet" ""
			(at 391.16 185.42 0)
			(effects
				(font
					(size 1.27 1.27)
				)
				(hide yes)
			)
		)
		(property "Description" ""
			(at 391.16 185.42 0)
			(effects
				(font
					(size 1.27 1.27)
				)
			)
		)
		(pin "1"
		)
		(instances
			(project "k410t-devboard"
				(path ""
					(reference "#PWR0442")
					(unit 1)
				)
			)
		)
	)
	(symbol
		(lib_id "antmicroResistors0402:R_10k_0402")
		(at 83.82 181.61 90)
		(unit 1)
		(exclude_from_sim no)
		(in_bom yes)
		(on_board yes)
		(dnp no)
		(property "Reference" "R67"
			(at 85.09 177.8 90)
			(effects
				(font
					(size 1.27 1.27)
				)
				(justify right)
			)
		)
		(property "Value" "R_10k_0402"
			(at 96.52 161.29 0)
			(effects
				(font
					(size 1.27 1.27)
					(thickness 0.15)
				)
				(justify left bottom)
				(hide yes)
			)
		)
		(property "Footprint" "antmicro-footprints:R_0402_1005Metric"
			(at 99.06 161.29 0)
			(effects
				(font
					(size 1.27 1.27)
					(thickness 0.15)
				)
				(justify left bottom)
				(hide yes)
			)
		)
		(property "Datasheet" "https://www.bourns.com/docs/product-datasheets/cr.pdf"
			(at 101.6 161.29 0)
			(effects
				(font
					(size 1.27 1.27)
					(thickness 0.15)
				)
				(justify left bottom)
				(hide yes)
			)
		)
		(property "Description" ""
			(at 83.82 181.61 0)
			(effects
				(font
					(size 1.27 1.27)
				)
			)
		)
		(property "Manufacturer" "Bourns"
			(at 106.68 161.29 0)
			(effects
				(font
					(size 1.27 1.27)
					(thickness 0.15)
				)
				(justify left bottom)
				(hide yes)
			)
		)
		(property "MPN" "CR0402-FX-1002GLF"
			(at 104.14 161.29 0)
			(effects
				(font
					(size 1.27 1.27)
					(thickness 0.15)
				)
				(justify left bottom)
				(hide yes)
			)
		)
		(property "Val" "10k"
			(at 85.09 180.34 90)
			(effects
				(font
					(size 1.27 1.27)
					(thickness 0.15)
				)
				(justify right)
			)
		)
		(property "License" "Apache-2.0"
			(at 109.22 161.29 0)
			(effects
				(font
					(size 1.27 1.27)
					(thickness 0.15)
				)
				(justify left bottom)
				(hide yes)
			)
		)
		(property "Author" "Antmicro"
			(at 111.76 161.29 0)
			(effects
				(font
					(size 1.27 1.27)
					(thickness 0.15)
				)
				(justify left bottom)
				(hide yes)
			)
		)
		(property "Tolerance" "1%"
			(at 93.98 161.29 0)
			(effects
				(font
					(size 1.27 1.27)
				)
				(justify left bottom)
				(hide yes)
			)
		)
		(pin "1"
		)
		(pin "2"
		)
		(instances
			(project "k410t-devboard"
				(path ""
					(reference "R67")
					(unit 1)
				)
			)
		)
	)
	(symbol
		(lib_id "antmicroResistors0402:R_100R_0402")
		(at 304.8 181.61 90)
		(unit 1)
		(exclude_from_sim no)
		(in_bom no)
		(on_board yes)
		(dnp yes)
		(property "Reference" "R96"
			(at 306.07 177.8 90)
			(effects
				(font
					(size 1.27 1.27)
				)
				(justify right)
			)
		)
		(property "Value" "R_100R_0402"
			(at 317.5 161.29 0)
			(effects
				(font
					(size 1.27 1.27)
					(thickness 0.15)
				)
				(justify left bottom)
				(hide yes)
			)
		)
		(property "Footprint" "antmicro-footprints:R_0402_1005Metric"
			(at 320.04 161.29 0)
			(effects
				(font
					(size 1.27 1.27)
					(thickness 0.15)
				)
				(justify left bottom)
				(hide yes)
			)
		)
		(property "Datasheet" "https://www.bourns.com/docs/product-datasheets/cr.pdf"
			(at 322.58 161.29 0)
			(effects
				(font
					(size 1.27 1.27)
					(thickness 0.15)
				)
				(justify left bottom)
				(hide yes)
			)
		)
		(property "Description" ""
			(at 304.8 181.61 0)
			(effects
				(font
					(size 1.27 1.27)
				)
			)
		)
		(property "Manufacturer" "Bourns"
			(at 327.66 161.29 0)
			(effects
				(font
					(size 1.27 1.27)
					(thickness 0.15)
				)
				(justify left bottom)
				(hide yes)
			)
		)
		(property "MPN" "CR0402-FX-1000GLF"
			(at 325.12 161.29 0)
			(effects
				(font
					(size 1.27 1.27)
					(thickness 0.15)
				)
				(justify left bottom)
				(hide yes)
			)
		)
		(property "Val" "100R"
			(at 306.07 180.34 90)
			(effects
				(font
					(size 1.27 1.27)
					(thickness 0.15)
				)
				(justify right)
			)
		)
		(property "DNP" "DNP"
			(at 304.8 177.165 0)
			(effects
				(font
					(size 1.27 1.27)
				)
				(justify right)
			)
		)
		(property "License" "Apache-2.0"
			(at 330.2 161.29 0)
			(effects
				(font
					(size 1.27 1.27)
					(thickness 0.15)
				)
				(justify left bottom)
				(hide yes)
			)
		)
		(property "Author" "Antmicro"
			(at 332.74 161.29 0)
			(effects
				(font
					(size 1.27 1.27)
					(thickness 0.15)
				)
				(justify left bottom)
				(hide yes)
			)
		)
		(property "Tolerance" "1%"
			(at 314.96 161.29 0)
			(effects
				(font
					(size 1.27 1.27)
				)
				(justify left bottom)
				(hide yes)
			)
		)
		(pin "1"
		)
		(pin "2"
		)
		(instances
			(project "k410t-devboard"
				(path ""
					(reference "R96")
					(unit 1)
				)
			)
		)
	)
	(symbol
		(lib_id "antmicropower:GND")
		(at 304.8 209.55 0)
		(unit 1)
		(exclude_from_sim no)
		(in_bom yes)
		(on_board yes)
		(dnp no)
		(property "Reference" "#PWR0126"
			(at 304.8 215.9 0)
			(effects
				(font
					(size 1.27 1.27)
				)
				(hide yes)
			)
		)
		(property "Value" "GND"
			(at 304.8 213.36 0)
			(effects
				(font
					(size 1.27 1.27)
				)
			)
		)
		(property "Footprint" ""
			(at 313.69 217.17 0)
			(effects
				(font
					(size 1.27 1.27)
					(thickness 0.15)
				)
				(justify left bottom)
				(hide yes)
			)
		)
		(property "Datasheet" ""
			(at 313.69 222.25 0)
			(effects
				(font
					(size 1.27 1.27)
					(thickness 0.15)
				)
				(justify left bottom)
				(hide yes)
			)
		)
		(property "Description" ""
			(at 304.8 209.55 0)
			(effects
				(font
					(size 1.27 1.27)
				)
			)
		)
		(property "Author" "Antmicro"
			(at 313.69 217.17 0)
			(effects
				(font
					(size 1.27 1.27)
					(thickness 0.15)
				)
				(justify left bottom)
				(hide yes)
			)
		)
		(property "License" "Apache-2.0"
			(at 313.69 219.71 0)
			(effects
				(font
					(size 1.27 1.27)
					(thickness 0.15)
				)
				(justify left bottom)
				(hide yes)
			)
		)
		(pin "1"
		)
		(instances
			(project "k410t-devboard"
				(path ""
					(reference "#PWR0126")
					(unit 1)
				)
			)
		)
	)
	(symbol
		(lib_id "antmicropower:GND")
		(at 379.73 200.66 0)
		(unit 1)
		(exclude_from_sim no)
		(in_bom yes)
		(on_board yes)
		(dnp no)
		(property "Reference" "#PWR0135"
			(at 379.73 207.01 0)
			(effects
				(font
					(size 1.27 1.27)
				)
				(hide yes)
			)
		)
		(property "Value" "GND"
			(at 379.73 204.47 0)
			(effects
				(font
					(size 1.27 1.27)
				)
			)
		)
		(property "Footprint" ""
			(at 388.62 208.28 0)
			(effects
				(font
					(size 1.27 1.27)
					(thickness 0.15)
				)
				(justify left bottom)
				(hide yes)
			)
		)
		(property "Datasheet" ""
			(at 388.62 213.36 0)
			(effects
				(font
					(size 1.27 1.27)
					(thickness 0.15)
				)
				(justify left bottom)
				(hide yes)
			)
		)
		(property "Description" ""
			(at 379.73 200.66 0)
			(effects
				(font
					(size 1.27 1.27)
				)
			)
		)
		(property "Author" "Antmicro"
			(at 388.62 208.28 0)
			(effects
				(font
					(size 1.27 1.27)
					(thickness 0.15)
				)
				(justify left bottom)
				(hide yes)
			)
		)
		(property "License" "Apache-2.0"
			(at 388.62 210.82 0)
			(effects
				(font
					(size 1.27 1.27)
					(thickness 0.15)
				)
				(justify left bottom)
				(hide yes)
			)
		)
		(pin "1"
		)
		(instances
			(project "k410t-devboard"
				(path ""
					(reference "#PWR0135")
					(unit 1)
				)
			)
		)
	)
	(symbol
		(lib_id "antmicroResistors0402:R_0R_0402")
		(at 316.23 186.69 0)
		(unit 1)
		(exclude_from_sim no)
		(in_bom yes)
		(on_board yes)
		(dnp no)
		(property "Reference" "R99"
			(at 323.215 185.42 0)
			(effects
				(font
					(size 1.27 1.27)
				)
			)
		)
		(property "Value" "R_0R_0402"
			(at 336.55 199.39 0)
			(effects
				(font
					(size 1.27 1.27)
					(thickness 0.15)
				)
				(justify left bottom)
				(hide yes)
			)
		)
		(property "Footprint" "antmicro-footprints:R_0402_1005Metric"
			(at 336.55 201.93 0)
			(effects
				(font
					(size 1.27 1.27)
					(thickness 0.15)
				)
				(justify left bottom)
				(hide yes)
			)
		)
		(property "Datasheet" "https://industrial.panasonic.com/cdbs/www-data/pdf/RDA0000/AOA0000C301.pdf"
			(at 336.55 204.47 0)
			(effects
				(font
					(size 1.27 1.27)
					(thickness 0.15)
				)
				(justify left bottom)
				(hide yes)
			)
		)
		(property "Description" ""
			(at 316.23 186.69 0)
			(effects
				(font
					(size 1.27 1.27)
				)
			)
		)
		(property "Manufacturer" "Panasonic"
			(at 336.55 209.55 0)
			(effects
				(font
					(size 1.27 1.27)
					(thickness 0.15)
				)
				(justify left bottom)
				(hide yes)
			)
		)
		(property "MPN" "ERJ2GE0R00X"
			(at 336.55 207.01 0)
			(effects
				(font
					(size 1.27 1.27)
					(thickness 0.15)
				)
				(justify left bottom)
				(hide yes)
			)
		)
		(property "Val" "0R"
			(at 314.96 185.42 0)
			(effects
				(font
					(size 1.27 1.27)
					(thickness 0.15)
				)
			)
		)
		(property "License" "Apache-2.0"
			(at 336.55 212.09 0)
			(effects
				(font
					(size 1.27 1.27)
					(thickness 0.15)
				)
				(justify left bottom)
				(hide yes)
			)
		)
		(property "Author" "Antmicro"
			(at 336.55 214.63 0)
			(effects
				(font
					(size 1.27 1.27)
					(thickness 0.15)
				)
				(justify left bottom)
				(hide yes)
			)
		)
		(property "Tolerance" "~"
			(at 336.55 196.85 0)
			(effects
				(font
					(size 1.27 1.27)
				)
				(justify left bottom)
				(hide yes)
			)
		)
		(property "Current" "1A"
			(at 336.55 217.17 0)
			(effects
				(font
					(size 1.27 1.27)
					(thickness 0.15)
				)
				(justify left bottom)
				(hide yes)
			)
		)
		(pin "1"
		)
		(pin "2"
		)
		(instances
			(project "k410t-devboard"
				(path ""
					(reference "R99")
					(unit 1)
				)
			)
		)
	)
	(symbol
		(lib_id "antmicroResistors0402:R_0R_0402")
		(at 316.23 194.31 0)
		(unit 1)
		(exclude_from_sim no)
		(in_bom yes)
		(on_board yes)
		(dnp no)
		(property "Reference" "R102"
			(at 323.85 193.04 0)
			(effects
				(font
					(size 1.27 1.27)
				)
			)
		)
		(property "Value" "R_0R_0402"
			(at 336.55 207.01 0)
			(effects
				(font
					(size 1.27 1.27)
					(thickness 0.15)
				)
				(justify left bottom)
				(hide yes)
			)
		)
		(property "Footprint" "antmicro-footprints:R_0402_1005Metric"
			(at 336.55 209.55 0)
			(effects
				(font
					(size 1.27 1.27)
					(thickness 0.15)
				)
				(justify left bottom)
				(hide yes)
			)
		)
		(property "Datasheet" "https://industrial.panasonic.com/cdbs/www-data/pdf/RDA0000/AOA0000C301.pdf"
			(at 336.55 212.09 0)
			(effects
				(font
					(size 1.27 1.27)
					(thickness 0.15)
				)
				(justify left bottom)
				(hide yes)
			)
		)
		(property "Description" ""
			(at 316.23 194.31 0)
			(effects
				(font
					(size 1.27 1.27)
				)
			)
		)
		(property "Manufacturer" "Panasonic"
			(at 336.55 217.17 0)
			(effects
				(font
					(size 1.27 1.27)
					(thickness 0.15)
				)
				(justify left bottom)
				(hide yes)
			)
		)
		(property "MPN" "ERJ2GE0R00X"
			(at 336.55 214.63 0)
			(effects
				(font
					(size 1.27 1.27)
					(thickness 0.15)
				)
				(justify left bottom)
				(hide yes)
			)
		)
		(property "Val" "0R"
			(at 314.96 193.04 0)
			(effects
				(font
					(size 1.27 1.27)
					(thickness 0.15)
				)
			)
		)
		(property "License" "Apache-2.0"
			(at 336.55 219.71 0)
			(effects
				(font
					(size 1.27 1.27)
					(thickness 0.15)
				)
				(justify left bottom)
				(hide yes)
			)
		)
		(property "Author" "Antmicro"
			(at 336.55 222.25 0)
			(effects
				(font
					(size 1.27 1.27)
					(thickness 0.15)
				)
				(justify left bottom)
				(hide yes)
			)
		)
		(property "Tolerance" "~"
			(at 336.55 204.47 0)
			(effects
				(font
					(size 1.27 1.27)
				)
				(justify left bottom)
				(hide yes)
			)
		)
		(property "Current" "1A"
			(at 336.55 224.79 0)
			(effects
				(font
					(size 1.27 1.27)
					(thickness 0.15)
				)
				(justify left bottom)
				(hide yes)
			)
		)
		(pin "1"
		)
		(pin "2"
		)
		(instances
			(project "k410t-devboard"
				(path ""
					(reference "R102")
					(unit 1)
				)
			)
		)
	)
	(symbol
		(lib_id "antmicroResistors0402:R_10k_0402")
		(at 238.76 66.04 180)
		(unit 1)
		(exclude_from_sim no)
		(in_bom yes)
		(on_board yes)
		(dnp no)
		(property "Reference" "R86"
			(at 240.665 64.77 0)
			(effects
				(font
					(size 1.27 1.27)
				)
			)
		)
		(property "Value" "R_10k_0402"
			(at 218.44 53.34 0)
			(effects
				(font
					(size 1.27 1.27)
					(thickness 0.15)
				)
				(justify left bottom)
				(hide yes)
			)
		)
		(property "Footprint" "antmicro-footprints:R_0402_1005Metric"
			(at 218.44 50.8 0)
			(effects
				(font
					(size 1.27 1.27)
					(thickness 0.15)
				)
				(justify left bottom)
				(hide yes)
			)
		)
		(property "Datasheet" "https://www.bourns.com/docs/product-datasheets/cr.pdf"
			(at 218.44 48.26 0)
			(effects
				(font
					(size 1.27 1.27)
					(thickness 0.15)
				)
				(justify left bottom)
				(hide yes)
			)
		)
		(property "Description" ""
			(at 238.76 66.04 0)
			(effects
				(font
					(size 1.27 1.27)
				)
			)
		)
		(property "Manufacturer" "Bourns"
			(at 218.44 43.18 0)
			(effects
				(font
					(size 1.27 1.27)
					(thickness 0.15)
				)
				(justify left bottom)
				(hide yes)
			)
		)
		(property "MPN" "CR0402-FX-1002GLF"
			(at 218.44 45.72 0)
			(effects
				(font
					(size 1.27 1.27)
					(thickness 0.15)
				)
				(justify left bottom)
				(hide yes)
			)
		)
		(property "Val" "10k"
			(at 231.775 64.77 0)
			(effects
				(font
					(size 1.27 1.27)
					(thickness 0.15)
				)
			)
		)
		(property "License" "Apache-2.0"
			(at 218.44 40.64 0)
			(effects
				(font
					(size 1.27 1.27)
					(thickness 0.15)
				)
				(justify left bottom)
				(hide yes)
			)
		)
		(property "Author" "Antmicro"
			(at 218.44 38.1 0)
			(effects
				(font
					(size 1.27 1.27)
					(thickness 0.15)
				)
				(justify left bottom)
				(hide yes)
			)
		)
		(property "Tolerance" "1%"
			(at 218.44 55.88 0)
			(effects
				(font
					(size 1.27 1.27)
				)
				(justify left bottom)
				(hide yes)
			)
		)
		(pin "1"
		)
		(pin "2"
		)
		(instances
			(project "k410t-devboard"
				(path ""
					(reference "R86")
					(unit 1)
				)
			)
		)
	)
	(symbol
		(lib_id "antmicroResistors0402:R_100R_0402")
		(at 317.5 86.36 180)
		(unit 1)
		(exclude_from_sim no)
		(in_bom yes)
		(on_board yes)
		(dnp no)
		(property "Reference" "R98"
			(at 319.405 85.09 0)
			(effects
				(font
					(size 1.27 1.27)
				)
			)
		)
		(property "Value" "R_100R_0402"
			(at 297.18 73.66 0)
			(effects
				(font
					(size 1.27 1.27)
					(thickness 0.15)
				)
				(justify left bottom)
				(hide yes)
			)
		)
		(property "Footprint" "antmicro-footprints:R_0402_1005Metric"
			(at 297.18 71.12 0)
			(effects
				(font
					(size 1.27 1.27)
					(thickness 0.15)
				)
				(justify left bottom)
				(hide yes)
			)
		)
		(property "Datasheet" "https://www.bourns.com/docs/product-datasheets/cr.pdf"
			(at 297.18 68.58 0)
			(effects
				(font
					(size 1.27 1.27)
					(thickness 0.15)
				)
				(justify left bottom)
				(hide yes)
			)
		)
		(property "Description" ""
			(at 317.5 86.36 0)
			(effects
				(font
					(size 1.27 1.27)
				)
			)
		)
		(property "Manufacturer" "Bourns"
			(at 297.18 63.5 0)
			(effects
				(font
					(size 1.27 1.27)
					(thickness 0.15)
				)
				(justify left bottom)
				(hide yes)
			)
		)
		(property "MPN" "CR0402-FX-1000GLF"
			(at 297.18 66.04 0)
			(effects
				(font
					(size 1.27 1.27)
					(thickness 0.15)
				)
				(justify left bottom)
				(hide yes)
			)
		)
		(property "Val" "100R"
			(at 309.88 85.09 0)
			(effects
				(font
					(size 1.27 1.27)
					(thickness 0.15)
				)
			)
		)
		(property "License" "Apache-2.0"
			(at 297.18 60.96 0)
			(effects
				(font
					(size 1.27 1.27)
					(thickness 0.15)
				)
				(justify left bottom)
				(hide yes)
			)
		)
		(property "Author" "Antmicro"
			(at 297.18 58.42 0)
			(effects
				(font
					(size 1.27 1.27)
					(thickness 0.15)
				)
				(justify left bottom)
				(hide yes)
			)
		)
		(property "Tolerance" "1%"
			(at 297.18 76.2 0)
			(effects
				(font
					(size 1.27 1.27)
				)
				(justify left bottom)
				(hide yes)
			)
		)
		(pin "1"
		)
		(pin "2"
		)
		(instances
			(project "k410t-devboard"
				(path ""
					(reference "R98")
					(unit 1)
				)
			)
		)
	)
	(symbol
		(lib_id "antmicroResistors0402:R_0R_0402")
		(at 316.23 196.85 0)
		(unit 1)
		(exclude_from_sim no)
		(in_bom yes)
		(on_board yes)
		(dnp no)
		(property "Reference" "R103"
			(at 323.85 195.58 0)
			(effects
				(font
					(size 1.27 1.27)
				)
			)
		)
		(property "Value" "R_0R_0402"
			(at 336.55 209.55 0)
			(effects
				(font
					(size 1.27 1.27)
					(thickness 0.15)
				)
				(justify left bottom)
				(hide yes)
			)
		)
		(property "Footprint" "antmicro-footprints:R_0402_1005Metric"
			(at 336.55 212.09 0)
			(effects
				(font
					(size 1.27 1.27)
					(thickness 0.15)
				)
				(justify left bottom)
				(hide yes)
			)
		)
		(property "Datasheet" "https://industrial.panasonic.com/cdbs/www-data/pdf/RDA0000/AOA0000C301.pdf"
			(at 336.55 214.63 0)
			(effects
				(font
					(size 1.27 1.27)
					(thickness 0.15)
				)
				(justify left bottom)
				(hide yes)
			)
		)
		(property "Description" ""
			(at 316.23 196.85 0)
			(effects
				(font
					(size 1.27 1.27)
				)
			)
		)
		(property "Manufacturer" "Panasonic"
			(at 336.55 219.71 0)
			(effects
				(font
					(size 1.27 1.27)
					(thickness 0.15)
				)
				(justify left bottom)
				(hide yes)
			)
		)
		(property "MPN" "ERJ2GE0R00X"
			(at 336.55 217.17 0)
			(effects
				(font
					(size 1.27 1.27)
					(thickness 0.15)
				)
				(justify left bottom)
				(hide yes)
			)
		)
		(property "Val" "0R"
			(at 314.96 195.58 0)
			(effects
				(font
					(size 1.27 1.27)
					(thickness 0.15)
				)
			)
		)
		(property "License" "Apache-2.0"
			(at 336.55 222.25 0)
			(effects
				(font
					(size 1.27 1.27)
					(thickness 0.15)
				)
				(justify left bottom)
				(hide yes)
			)
		)
		(property "Author" "Antmicro"
			(at 336.55 224.79 0)
			(effects
				(font
					(size 1.27 1.27)
					(thickness 0.15)
				)
				(justify left bottom)
				(hide yes)
			)
		)
		(property "Tolerance" "~"
			(at 336.55 207.01 0)
			(effects
				(font
					(size 1.27 1.27)
				)
				(justify left bottom)
				(hide yes)
			)
		)
		(property "Current" "1A"
			(at 336.55 227.33 0)
			(effects
				(font
					(size 1.27 1.27)
					(thickness 0.15)
				)
				(justify left bottom)
				(hide yes)
			)
		)
		(pin "1"
		)
		(pin "2"
		)
		(instances
			(project "k410t-devboard"
				(path ""
					(reference "R103")
					(unit 1)
				)
			)
		)
	)
	(symbol
		(lib_id "antmicroResistors0402:R_10k_0402")
		(at 238.76 71.12 180)
		(unit 1)
		(exclude_from_sim no)
		(in_bom yes)
		(on_board yes)
		(dnp no)
		(property "Reference" "R88"
			(at 240.665 69.85 0)
			(effects
				(font
					(size 1.27 1.27)
				)
			)
		)
		(property "Value" "R_10k_0402"
			(at 218.44 58.42 0)
			(effects
				(font
					(size 1.27 1.27)
					(thickness 0.15)
				)
				(justify left bottom)
				(hide yes)
			)
		)
		(property "Footprint" "antmicro-footprints:R_0402_1005Metric"
			(at 218.44 55.88 0)
			(effects
				(font
					(size 1.27 1.27)
					(thickness 0.15)
				)
				(justify left bottom)
				(hide yes)
			)
		)
		(property "Datasheet" "https://www.bourns.com/docs/product-datasheets/cr.pdf"
			(at 218.44 53.34 0)
			(effects
				(font
					(size 1.27 1.27)
					(thickness 0.15)
				)
				(justify left bottom)
				(hide yes)
			)
		)
		(property "Description" ""
			(at 238.76 71.12 0)
			(effects
				(font
					(size 1.27 1.27)
				)
			)
		)
		(property "Manufacturer" "Bourns"
			(at 218.44 48.26 0)
			(effects
				(font
					(size 1.27 1.27)
					(thickness 0.15)
				)
				(justify left bottom)
				(hide yes)
			)
		)
		(property "MPN" "CR0402-FX-1002GLF"
			(at 218.44 50.8 0)
			(effects
				(font
					(size 1.27 1.27)
					(thickness 0.15)
				)
				(justify left bottom)
				(hide yes)
			)
		)
		(property "Val" "10k"
			(at 231.775 69.85 0)
			(effects
				(font
					(size 1.27 1.27)
					(thickness 0.15)
				)
			)
		)
		(property "License" "Apache-2.0"
			(at 218.44 45.72 0)
			(effects
				(font
					(size 1.27 1.27)
					(thickness 0.15)
				)
				(justify left bottom)
				(hide yes)
			)
		)
		(property "Author" "Antmicro"
			(at 218.44 43.18 0)
			(effects
				(font
					(size 1.27 1.27)
					(thickness 0.15)
				)
				(justify left bottom)
				(hide yes)
			)
		)
		(property "Tolerance" "1%"
			(at 218.44 60.96 0)
			(effects
				(font
					(size 1.27 1.27)
				)
				(justify left bottom)
				(hide yes)
			)
		)
		(pin "1"
		)
		(pin "2"
		)
		(instances
			(project "k410t-devboard"
				(path ""
					(reference "R88")
					(unit 1)
				)
			)
		)
	)
	(symbol
		(lib_id "antmicroResistors0402:R_0R_0402")
		(at 110.49 78.74 0)
		(unit 1)
		(exclude_from_sim no)
		(in_bom yes)
		(on_board yes)
		(dnp no)
		(property "Reference" "R79"
			(at 117.475 77.47 0)
			(effects
				(font
					(size 1.27 1.27)
				)
			)
		)
		(property "Value" "R_0R_0402"
			(at 130.81 91.44 0)
			(effects
				(font
					(size 1.27 1.27)
					(thickness 0.15)
				)
				(justify left bottom)
				(hide yes)
			)
		)
		(property "Footprint" "antmicro-footprints:R_0402_1005Metric"
			(at 130.81 93.98 0)
			(effects
				(font
					(size 1.27 1.27)
					(thickness 0.15)
				)
				(justify left bottom)
				(hide yes)
			)
		)
		(property "Datasheet" "https://industrial.panasonic.com/cdbs/www-data/pdf/RDA0000/AOA0000C301.pdf"
			(at 130.81 96.52 0)
			(effects
				(font
					(size 1.27 1.27)
					(thickness 0.15)
				)
				(justify left bottom)
				(hide yes)
			)
		)
		(property "Description" ""
			(at 110.49 78.74 0)
			(effects
				(font
					(size 1.27 1.27)
				)
			)
		)
		(property "Manufacturer" "Panasonic"
			(at 130.81 101.6 0)
			(effects
				(font
					(size 1.27 1.27)
					(thickness 0.15)
				)
				(justify left bottom)
				(hide yes)
			)
		)
		(property "MPN" "ERJ2GE0R00X"
			(at 130.81 99.06 0)
			(effects
				(font
					(size 1.27 1.27)
					(thickness 0.15)
				)
				(justify left bottom)
				(hide yes)
			)
		)
		(property "Val" "0R"
			(at 109.22 77.47 0)
			(effects
				(font
					(size 1.27 1.27)
					(thickness 0.15)
				)
			)
		)
		(property "License" "Apache-2.0"
			(at 130.81 104.14 0)
			(effects
				(font
					(size 1.27 1.27)
					(thickness 0.15)
				)
				(justify left bottom)
				(hide yes)
			)
		)
		(property "Author" "Antmicro"
			(at 130.81 106.68 0)
			(effects
				(font
					(size 1.27 1.27)
					(thickness 0.15)
				)
				(justify left bottom)
				(hide yes)
			)
		)
		(property "Tolerance" "~"
			(at 130.81 88.9 0)
			(effects
				(font
					(size 1.27 1.27)
				)
				(justify left bottom)
				(hide yes)
			)
		)
		(property "Current" "1A"
			(at 130.81 109.22 0)
			(effects
				(font
					(size 1.27 1.27)
					(thickness 0.15)
				)
				(justify left bottom)
				(hide yes)
			)
		)
		(pin "1"
		)
		(pin "2"
		)
		(instances
			(project "k410t-devboard"
				(path ""
					(reference "R79")
					(unit 1)
				)
			)
		)
	)
	(symbol
		(lib_id "antmicropower:GND")
		(at 101.6 88.9 0)
		(unit 1)
		(exclude_from_sim no)
		(in_bom yes)
		(on_board yes)
		(dnp no)
		(property "Reference" "#PWR0118"
			(at 101.6 95.25 0)
			(effects
				(font
					(size 1.27 1.27)
				)
				(hide yes)
			)
		)
		(property "Value" "GND"
			(at 101.6 92.71 0)
			(effects
				(font
					(size 1.27 1.27)
				)
			)
		)
		(property "Footprint" ""
			(at 110.49 96.52 0)
			(effects
				(font
					(size 1.27 1.27)
					(thickness 0.15)
				)
				(justify left bottom)
				(hide yes)
			)
		)
		(property "Datasheet" ""
			(at 110.49 101.6 0)
			(effects
				(font
					(size 1.27 1.27)
					(thickness 0.15)
				)
				(justify left bottom)
				(hide yes)
			)
		)
		(property "Description" ""
			(at 101.6 88.9 0)
			(effects
				(font
					(size 1.27 1.27)
				)
			)
		)
		(property "Author" "Antmicro"
			(at 110.49 96.52 0)
			(effects
				(font
					(size 1.27 1.27)
					(thickness 0.15)
				)
				(justify left bottom)
				(hide yes)
			)
		)
		(property "License" "Apache-2.0"
			(at 110.49 99.06 0)
			(effects
				(font
					(size 1.27 1.27)
					(thickness 0.15)
				)
				(justify left bottom)
				(hide yes)
			)
		)
		(pin "1"
		)
		(instances
			(project "k410t-devboard"
				(path ""
					(reference "#PWR0118")
					(unit 1)
				)
			)
		)
	)
	(symbol
		(lib_id "antmicroResistors0402:R_10k_0402")
		(at 238.76 83.82 180)
		(unit 1)
		(exclude_from_sim no)
		(in_bom yes)
		(on_board yes)
		(dnp no)
		(property "Reference" "R91"
			(at 240.665 82.55 0)
			(effects
				(font
					(size 1.27 1.27)
				)
			)
		)
		(property "Value" "R_10k_0402"
			(at 218.44 71.12 0)
			(effects
				(font
					(size 1.27 1.27)
					(thickness 0.15)
				)
				(justify left bottom)
				(hide yes)
			)
		)
		(property "Footprint" "antmicro-footprints:R_0402_1005Metric"
			(at 218.44 68.58 0)
			(effects
				(font
					(size 1.27 1.27)
					(thickness 0.15)
				)
				(justify left bottom)
				(hide yes)
			)
		)
		(property "Datasheet" "https://www.bourns.com/docs/product-datasheets/cr.pdf"
			(at 218.44 66.04 0)
			(effects
				(font
					(size 1.27 1.27)
					(thickness 0.15)
				)
				(justify left bottom)
				(hide yes)
			)
		)
		(property "Description" ""
			(at 238.76 83.82 0)
			(effects
				(font
					(size 1.27 1.27)
				)
			)
		)
		(property "Manufacturer" "Bourns"
			(at 218.44 60.96 0)
			(effects
				(font
					(size 1.27 1.27)
					(thickness 0.15)
				)
				(justify left bottom)
				(hide yes)
			)
		)
		(property "MPN" "CR0402-FX-1002GLF"
			(at 218.44 63.5 0)
			(effects
				(font
					(size 1.27 1.27)
					(thickness 0.15)
				)
				(justify left bottom)
				(hide yes)
			)
		)
		(property "Val" "10k"
			(at 231.775 82.55 0)
			(effects
				(font
					(size 1.27 1.27)
					(thickness 0.15)
				)
			)
		)
		(property "License" "Apache-2.0"
			(at 218.44 58.42 0)
			(effects
				(font
					(size 1.27 1.27)
					(thickness 0.15)
				)
				(justify left bottom)
				(hide yes)
			)
		)
		(property "Author" "Antmicro"
			(at 218.44 55.88 0)
			(effects
				(font
					(size 1.27 1.27)
					(thickness 0.15)
				)
				(justify left bottom)
				(hide yes)
			)
		)
		(property "Tolerance" "1%"
			(at 218.44 73.66 0)
			(effects
				(font
					(size 1.27 1.27)
				)
				(justify left bottom)
				(hide yes)
			)
		)
		(pin "1"
		)
		(pin "2"
		)
		(instances
			(project "k410t-devboard"
				(path ""
					(reference "R91")
					(unit 1)
				)
			)
		)
	)
	(symbol
		(lib_id "antmicroResistors0402:R_0R_0402")
		(at 110.49 71.12 0)
		(unit 1)
		(exclude_from_sim no)
		(in_bom yes)
		(on_board yes)
		(dnp no)
		(property "Reference" "R76"
			(at 117.475 69.85 0)
			(effects
				(font
					(size 1.27 1.27)
				)
			)
		)
		(property "Value" "R_0R_0402"
			(at 130.81 83.82 0)
			(effects
				(font
					(size 1.27 1.27)
					(thickness 0.15)
				)
				(justify left bottom)
				(hide yes)
			)
		)
		(property "Footprint" "antmicro-footprints:R_0402_1005Metric"
			(at 130.81 86.36 0)
			(effects
				(font
					(size 1.27 1.27)
					(thickness 0.15)
				)
				(justify left bottom)
				(hide yes)
			)
		)
		(property "Datasheet" "https://industrial.panasonic.com/cdbs/www-data/pdf/RDA0000/AOA0000C301.pdf"
			(at 130.81 88.9 0)
			(effects
				(font
					(size 1.27 1.27)
					(thickness 0.15)
				)
				(justify left bottom)
				(hide yes)
			)
		)
		(property "Description" ""
			(at 110.49 71.12 0)
			(effects
				(font
					(size 1.27 1.27)
				)
			)
		)
		(property "Manufacturer" "Panasonic"
			(at 130.81 93.98 0)
			(effects
				(font
					(size 1.27 1.27)
					(thickness 0.15)
				)
				(justify left bottom)
				(hide yes)
			)
		)
		(property "MPN" "ERJ2GE0R00X"
			(at 130.81 91.44 0)
			(effects
				(font
					(size 1.27 1.27)
					(thickness 0.15)
				)
				(justify left bottom)
				(hide yes)
			)
		)
		(property "Val" "0R"
			(at 109.22 69.85 0)
			(effects
				(font
					(size 1.27 1.27)
					(thickness 0.15)
				)
			)
		)
		(property "License" "Apache-2.0"
			(at 130.81 96.52 0)
			(effects
				(font
					(size 1.27 1.27)
					(thickness 0.15)
				)
				(justify left bottom)
				(hide yes)
			)
		)
		(property "Author" "Antmicro"
			(at 130.81 99.06 0)
			(effects
				(font
					(size 1.27 1.27)
					(thickness 0.15)
				)
				(justify left bottom)
				(hide yes)
			)
		)
		(property "Tolerance" "~"
			(at 130.81 81.28 0)
			(effects
				(font
					(size 1.27 1.27)
				)
				(justify left bottom)
				(hide yes)
			)
		)
		(property "Current" "1A"
			(at 130.81 101.6 0)
			(effects
				(font
					(size 1.27 1.27)
					(thickness 0.15)
				)
				(justify left bottom)
				(hide yes)
			)
		)
		(pin "1"
		)
		(pin "2"
		)
		(instances
			(project "k410t-devboard"
				(path ""
					(reference "R76")
					(unit 1)
				)
			)
		)
	)
	(symbol
		(lib_id "antmicroCapacitors0402:C_100n_0402")
		(at 177.8 74.93 90)
		(unit 1)
		(exclude_from_sim no)
		(in_bom yes)
		(on_board yes)
		(dnp no)
		(fields_autoplaced yes)
		(property "Reference" "C209"
			(at 180.34 71.1135 90)
			(effects
				(font
					(size 1.27 1.27)
				)
				(justify right)
			)
		)
		(property "Value" "C_100n_0402"
			(at 187.96 54.61 0)
			(effects
				(font
					(size 1.27 1.27)
					(thickness 0.15)
				)
				(justify left bottom)
				(hide yes)
			)
		)
		(property "Footprint" "antmicro-footprints:C_0402_1005Metric"
			(at 190.5 54.61 0)
			(effects
				(font
					(size 1.27 1.27)
					(thickness 0.15)
				)
				(justify left bottom)
				(hide yes)
			)
		)
		(property "Datasheet" "https://www.murata.com/products/productdetail?partno=GRM155R61H104KE14%23"
			(at 193.04 54.61 0)
			(effects
				(font
					(size 1.27 1.27)
					(thickness 0.15)
				)
				(justify left bottom)
				(hide yes)
			)
		)
		(property "Description" ""
			(at 177.8 74.93 0)
			(effects
				(font
					(size 1.27 1.27)
				)
			)
		)
		(property "Manufacturer" "Murata"
			(at 198.12 54.61 0)
			(effects
				(font
					(size 1.27 1.27)
					(thickness 0.15)
				)
				(justify left bottom)
				(hide yes)
			)
		)
		(property "MPN" "GRM155R61H104KE14D"
			(at 195.58 54.61 0)
			(effects
				(font
					(size 1.27 1.27)
					(thickness 0.15)
				)
				(justify left bottom)
				(hide yes)
			)
		)
		(property "Val" "100n"
			(at 180.34 73.6535 90)
			(effects
				(font
					(size 1.27 1.27)
					(thickness 0.15)
				)
				(justify right)
			)
		)
		(property "License" "Apache-2.0"
			(at 200.66 54.61 0)
			(effects
				(font
					(size 1.27 1.27)
					(thickness 0.15)
				)
				(justify left bottom)
				(hide yes)
			)
		)
		(property "Author" "Antmicro"
			(at 203.2 54.61 0)
			(effects
				(font
					(size 1.27 1.27)
					(thickness 0.15)
				)
				(justify left bottom)
				(hide yes)
			)
		)
		(property "Voltage" "50V"
			(at 205.74 54.61 0)
			(effects
				(font
					(size 1.27 1.27)
				)
				(justify left bottom)
				(hide yes)
			)
		)
		(property "Dielectric" "X5R"
			(at 208.28 54.61 0)
			(effects
				(font
					(size 1.27 1.27)
				)
				(justify left bottom)
				(hide yes)
			)
		)
		(pin "1"
		)
		(pin "2"
		)
		(instances
			(project "k410t-devboard"
				(path ""
					(reference "C209")
					(unit 1)
				)
			)
		)
	)
	(symbol
		(lib_id "antmicroResistors0402:R_10k_0402")
		(at 92.71 181.61 90)
		(unit 1)
		(exclude_from_sim no)
		(in_bom yes)
		(on_board yes)
		(dnp no)
		(property "Reference" "R69"
			(at 93.98 177.8 90)
			(effects
				(font
					(size 1.27 1.27)
				)
				(justify right)
			)
		)
		(property "Value" "R_10k_0402"
			(at 105.41 161.29 0)
			(effects
				(font
					(size 1.27 1.27)
					(thickness 0.15)
				)
				(justify left bottom)
				(hide yes)
			)
		)
		(property "Footprint" "antmicro-footprints:R_0402_1005Metric"
			(at 107.95 161.29 0)
			(effects
				(font
					(size 1.27 1.27)
					(thickness 0.15)
				)
				(justify left bottom)
				(hide yes)
			)
		)
		(property "Datasheet" "https://www.bourns.com/docs/product-datasheets/cr.pdf"
			(at 110.49 161.29 0)
			(effects
				(font
					(size 1.27 1.27)
					(thickness 0.15)
				)
				(justify left bottom)
				(hide yes)
			)
		)
		(property "Description" ""
			(at 92.71 181.61 0)
			(effects
				(font
					(size 1.27 1.27)
				)
			)
		)
		(property "Manufacturer" "Bourns"
			(at 115.57 161.29 0)
			(effects
				(font
					(size 1.27 1.27)
					(thickness 0.15)
				)
				(justify left bottom)
				(hide yes)
			)
		)
		(property "MPN" "CR0402-FX-1002GLF"
			(at 113.03 161.29 0)
			(effects
				(font
					(size 1.27 1.27)
					(thickness 0.15)
				)
				(justify left bottom)
				(hide yes)
			)
		)
		(property "Val" "10k"
			(at 93.98 180.34 90)
			(effects
				(font
					(size 1.27 1.27)
					(thickness 0.15)
				)
				(justify right)
			)
		)
		(property "License" "Apache-2.0"
			(at 118.11 161.29 0)
			(effects
				(font
					(size 1.27 1.27)
					(thickness 0.15)
				)
				(justify left bottom)
				(hide yes)
			)
		)
		(property "Author" "Antmicro"
			(at 120.65 161.29 0)
			(effects
				(font
					(size 1.27 1.27)
					(thickness 0.15)
				)
				(justify left bottom)
				(hide yes)
			)
		)
		(property "Tolerance" "1%"
			(at 102.87 161.29 0)
			(effects
				(font
					(size 1.27 1.27)
				)
				(justify left bottom)
				(hide yes)
			)
		)
		(pin "1"
		)
		(pin "2"
		)
		(instances
			(project "k410t-devboard"
				(path ""
					(reference "R69")
					(unit 1)
				)
			)
		)
	)
	(symbol
		(lib_id "antmicropower:GND")
		(at 177.8 80.01 0)
		(unit 1)
		(exclude_from_sim no)
		(in_bom yes)
		(on_board yes)
		(dnp no)
		(property "Reference" "#PWR0125"
			(at 177.8 86.36 0)
			(effects
				(font
					(size 1.27 1.27)
				)
				(hide yes)
			)
		)
		(property "Value" "GND"
			(at 177.8 83.82 0)
			(effects
				(font
					(size 1.27 1.27)
				)
			)
		)
		(property "Footprint" ""
			(at 186.69 87.63 0)
			(effects
				(font
					(size 1.27 1.27)
					(thickness 0.15)
				)
				(justify left bottom)
				(hide yes)
			)
		)
		(property "Datasheet" ""
			(at 186.69 92.71 0)
			(effects
				(font
					(size 1.27 1.27)
					(thickness 0.15)
				)
				(justify left bottom)
				(hide yes)
			)
		)
		(property "Description" ""
			(at 177.8 80.01 0)
			(effects
				(font
					(size 1.27 1.27)
				)
			)
		)
		(property "Author" "Antmicro"
			(at 186.69 87.63 0)
			(effects
				(font
					(size 1.27 1.27)
					(thickness 0.15)
				)
				(justify left bottom)
				(hide yes)
			)
		)
		(property "License" "Apache-2.0"
			(at 186.69 90.17 0)
			(effects
				(font
					(size 1.27 1.27)
					(thickness 0.15)
				)
				(justify left bottom)
				(hide yes)
			)
		)
		(pin "1"
		)
		(instances
			(project "k410t-devboard"
				(path ""
					(reference "#PWR0125")
					(unit 1)
				)
			)
		)
	)
	(symbol
		(lib_id "antmicropower:+1V8")
		(at 74.93 172.72 0)
		(unit 1)
		(exclude_from_sim no)
		(in_bom yes)
		(on_board yes)
		(dnp no)
		(fields_autoplaced yes)
		(property "Reference" "#PWR0115"
			(at 74.93 176.53 0)
			(effects
				(font
					(size 1.27 1.27)
				)
				(hide yes)
			)
		)
		(property "Value" "+1V8"
			(at 74.93 169.164 0)
			(effects
				(font
					(size 1.27 1.27)
				)
			)
		)
		(property "Footprint" ""
			(at 90.17 180.34 0)
			(effects
				(font
					(size 1.27 1.27)
					(thickness 0.15)
				)
				(justify left bottom)
				(hide yes)
			)
		)
		(property "Datasheet" ""
			(at 90.17 182.88 0)
			(effects
				(font
					(size 1.27 1.27)
					(thickness 0.15)
				)
				(justify left bottom)
				(hide yes)
			)
		)
		(property "Description" ""
			(at 74.93 172.72 0)
			(effects
				(font
					(size 1.27 1.27)
				)
			)
		)
		(property "Author" "Antmicro"
			(at 90.17 180.34 0)
			(effects
				(font
					(size 1.27 1.27)
					(thickness 0.15)
				)
				(justify left bottom)
				(hide yes)
			)
		)
		(property "License" "Apache-2.0"
			(at 90.17 182.88 0)
			(effects
				(font
					(size 1.27 1.27)
					(thickness 0.15)
				)
				(justify left bottom)
				(hide yes)
			)
		)
		(pin "1"
		)
		(instances
			(project "k410t-devboard"
				(path ""
					(reference "#PWR0115")
					(unit 1)
				)
			)
		)
	)
	(symbol
		(lib_id "antmicroResistors0402:R_10k_0402")
		(at 238.76 68.58 180)
		(unit 1)
		(exclude_from_sim no)
		(in_bom yes)
		(on_board yes)
		(dnp no)
		(property "Reference" "R87"
			(at 240.665 67.31 0)
			(effects
				(font
					(size 1.27 1.27)
				)
			)
		)
		(property "Value" "R_10k_0402"
			(at 218.44 55.88 0)
			(effects
				(font
					(size 1.27 1.27)
					(thickness 0.15)
				)
				(justify left bottom)
				(hide yes)
			)
		)
		(property "Footprint" "antmicro-footprints:R_0402_1005Metric"
			(at 218.44 53.34 0)
			(effects
				(font
					(size 1.27 1.27)
					(thickness 0.15)
				)
				(justify left bottom)
				(hide yes)
			)
		)
		(property "Datasheet" "https://www.bourns.com/docs/product-datasheets/cr.pdf"
			(at 218.44 50.8 0)
			(effects
				(font
					(size 1.27 1.27)
					(thickness 0.15)
				)
				(justify left bottom)
				(hide yes)
			)
		)
		(property "Description" ""
			(at 238.76 68.58 0)
			(effects
				(font
					(size 1.27 1.27)
				)
			)
		)
		(property "Manufacturer" "Bourns"
			(at 218.44 45.72 0)
			(effects
				(font
					(size 1.27 1.27)
					(thickness 0.15)
				)
				(justify left bottom)
				(hide yes)
			)
		)
		(property "MPN" "CR0402-FX-1002GLF"
			(at 218.44 48.26 0)
			(effects
				(font
					(size 1.27 1.27)
					(thickness 0.15)
				)
				(justify left bottom)
				(hide yes)
			)
		)
		(property "Val" "10k"
			(at 231.775 67.31 0)
			(effects
				(font
					(size 1.27 1.27)
					(thickness 0.15)
				)
			)
		)
		(property "License" "Apache-2.0"
			(at 218.44 43.18 0)
			(effects
				(font
					(size 1.27 1.27)
					(thickness 0.15)
				)
				(justify left bottom)
				(hide yes)
			)
		)
		(property "Author" "Antmicro"
			(at 218.44 40.64 0)
			(effects
				(font
					(size 1.27 1.27)
					(thickness 0.15)
				)
				(justify left bottom)
				(hide yes)
			)
		)
		(property "Tolerance" "1%"
			(at 218.44 58.42 0)
			(effects
				(font
					(size 1.27 1.27)
				)
				(justify left bottom)
				(hide yes)
			)
		)
		(pin "1"
		)
		(pin "2"
		)
		(instances
			(project "k410t-devboard"
				(path ""
					(reference "R87")
					(unit 1)
				)
			)
		)
	)
	(symbol
		(lib_id "antmicropower:GND")
		(at 392.43 100.33 0)
		(unit 1)
		(exclude_from_sim no)
		(in_bom yes)
		(on_board yes)
		(dnp no)
		(property "Reference" "#PWR0136"
			(at 392.43 106.68 0)
			(effects
				(font
					(size 1.27 1.27)
				)
				(hide yes)
			)
		)
		(property "Value" "GND"
			(at 392.43 104.14 0)
			(effects
				(font
					(size 1.27 1.27)
				)
			)
		)
		(property "Footprint" ""
			(at 401.32 107.95 0)
			(effects
				(font
					(size 1.27 1.27)
					(thickness 0.15)
				)
				(justify left bottom)
				(hide yes)
			)
		)
		(property "Datasheet" ""
			(at 401.32 113.03 0)
			(effects
				(font
					(size 1.27 1.27)
					(thickness 0.15)
				)
				(justify left bottom)
				(hide yes)
			)
		)
		(property "Description" ""
			(at 392.43 100.33 0)
			(effects
				(font
					(size 1.27 1.27)
				)
			)
		)
		(property "Author" "Antmicro"
			(at 401.32 107.95 0)
			(effects
				(font
					(size 1.27 1.27)
					(thickness 0.15)
				)
				(justify left bottom)
				(hide yes)
			)
		)
		(property "License" "Apache-2.0"
			(at 401.32 110.49 0)
			(effects
				(font
					(size 1.27 1.27)
					(thickness 0.15)
				)
				(justify left bottom)
				(hide yes)
			)
		)
		(pin "1"
		)
		(instances
			(project "k410t-devboard"
				(path ""
					(reference "#PWR0136")
					(unit 1)
				)
			)
		)
	)
	(symbol
		(lib_id "antmicroResistors0402:R_0R_0402")
		(at 316.23 191.77 0)
		(unit 1)
		(exclude_from_sim no)
		(in_bom yes)
		(on_board yes)
		(dnp no)
		(property "Reference" "R101"
			(at 323.85 190.5 0)
			(effects
				(font
					(size 1.27 1.27)
				)
			)
		)
		(property "Value" "R_0R_0402"
			(at 336.55 204.47 0)
			(effects
				(font
					(size 1.27 1.27)
					(thickness 0.15)
				)
				(justify left bottom)
				(hide yes)
			)
		)
		(property "Footprint" "antmicro-footprints:R_0402_1005Metric"
			(at 336.55 207.01 0)
			(effects
				(font
					(size 1.27 1.27)
					(thickness 0.15)
				)
				(justify left bottom)
				(hide yes)
			)
		)
		(property "Datasheet" "https://industrial.panasonic.com/cdbs/www-data/pdf/RDA0000/AOA0000C301.pdf"
			(at 336.55 209.55 0)
			(effects
				(font
					(size 1.27 1.27)
					(thickness 0.15)
				)
				(justify left bottom)
				(hide yes)
			)
		)
		(property "Description" ""
			(at 316.23 191.77 0)
			(effects
				(font
					(size 1.27 1.27)
				)
			)
		)
		(property "Manufacturer" "Panasonic"
			(at 336.55 214.63 0)
			(effects
				(font
					(size 1.27 1.27)
					(thickness 0.15)
				)
				(justify left bottom)
				(hide yes)
			)
		)
		(property "MPN" "ERJ2GE0R00X"
			(at 336.55 212.09 0)
			(effects
				(font
					(size 1.27 1.27)
					(thickness 0.15)
				)
				(justify left bottom)
				(hide yes)
			)
		)
		(property "Val" "0R"
			(at 314.96 190.5 0)
			(effects
				(font
					(size 1.27 1.27)
					(thickness 0.15)
				)
			)
		)
		(property "License" "Apache-2.0"
			(at 336.55 217.17 0)
			(effects
				(font
					(size 1.27 1.27)
					(thickness 0.15)
				)
				(justify left bottom)
				(hide yes)
			)
		)
		(property "Author" "Antmicro"
			(at 336.55 219.71 0)
			(effects
				(font
					(size 1.27 1.27)
					(thickness 0.15)
				)
				(justify left bottom)
				(hide yes)
			)
		)
		(property "Tolerance" "~"
			(at 336.55 201.93 0)
			(effects
				(font
					(size 1.27 1.27)
				)
				(justify left bottom)
				(hide yes)
			)
		)
		(property "Current" "1A"
			(at 336.55 222.25 0)
			(effects
				(font
					(size 1.27 1.27)
					(thickness 0.15)
				)
				(justify left bottom)
				(hide yes)
			)
		)
		(pin "1"
		)
		(pin "2"
		)
		(instances
			(project "k410t-devboard"
				(path ""
					(reference "R101")
					(unit 1)
				)
			)
		)
	)
	(symbol
		(lib_id "antmicroResistors0402:R_10k_0402")
		(at 74.93 181.61 90)
		(unit 1)
		(exclude_from_sim no)
		(in_bom yes)
		(on_board yes)
		(dnp no)
		(property "Reference" "R65"
			(at 76.2 177.8 90)
			(effects
				(font
					(size 1.27 1.27)
				)
				(justify right)
			)
		)
		(property "Value" "R_10k_0402"
			(at 87.63 161.29 0)
			(effects
				(font
					(size 1.27 1.27)
					(thickness 0.15)
				)
				(justify left bottom)
				(hide yes)
			)
		)
		(property "Footprint" "antmicro-footprints:R_0402_1005Metric"
			(at 90.17 161.29 0)
			(effects
				(font
					(size 1.27 1.27)
					(thickness 0.15)
				)
				(justify left bottom)
				(hide yes)
			)
		)
		(property "Datasheet" "https://www.bourns.com/docs/product-datasheets/cr.pdf"
			(at 92.71 161.29 0)
			(effects
				(font
					(size 1.27 1.27)
					(thickness 0.15)
				)
				(justify left bottom)
				(hide yes)
			)
		)
		(property "Description" ""
			(at 74.93 181.61 0)
			(effects
				(font
					(size 1.27 1.27)
				)
			)
		)
		(property "Manufacturer" "Bourns"
			(at 97.79 161.29 0)
			(effects
				(font
					(size 1.27 1.27)
					(thickness 0.15)
				)
				(justify left bottom)
				(hide yes)
			)
		)
		(property "MPN" "CR0402-FX-1002GLF"
			(at 95.25 161.29 0)
			(effects
				(font
					(size 1.27 1.27)
					(thickness 0.15)
				)
				(justify left bottom)
				(hide yes)
			)
		)
		(property "Val" "10k"
			(at 76.2 180.34 90)
			(effects
				(font
					(size 1.27 1.27)
					(thickness 0.15)
				)
				(justify right)
			)
		)
		(property "License" "Apache-2.0"
			(at 100.33 161.29 0)
			(effects
				(font
					(size 1.27 1.27)
					(thickness 0.15)
				)
				(justify left bottom)
				(hide yes)
			)
		)
		(property "Author" "Antmicro"
			(at 102.87 161.29 0)
			(effects
				(font
					(size 1.27 1.27)
					(thickness 0.15)
				)
				(justify left bottom)
				(hide yes)
			)
		)
		(property "Tolerance" "1%"
			(at 85.09 161.29 0)
			(effects
				(font
					(size 1.27 1.27)
				)
				(justify left bottom)
				(hide yes)
			)
		)
		(pin "1"
		)
		(pin "2"
		)
		(instances
			(project "k410t-devboard"
				(path ""
					(reference "R65")
					(unit 1)
				)
			)
		)
	)
	(symbol
		(lib_id "antmicroResistors0402:R_0R_0402")
		(at 111.76 189.23 0)
		(unit 1)
		(exclude_from_sim no)
		(in_bom yes)
		(on_board yes)
		(dnp no)
		(property "Reference" "R81"
			(at 118.745 187.96 0)
			(effects
				(font
					(size 1.27 1.27)
				)
			)
		)
		(property "Value" "R_0R_0402"
			(at 132.08 201.93 0)
			(effects
				(font
					(size 1.27 1.27)
					(thickness 0.15)
				)
				(justify left bottom)
				(hide yes)
			)
		)
		(property "Footprint" "antmicro-footprints:R_0402_1005Metric"
			(at 132.08 204.47 0)
			(effects
				(font
					(size 1.27 1.27)
					(thickness 0.15)
				)
				(justify left bottom)
				(hide yes)
			)
		)
		(property "Datasheet" "https://industrial.panasonic.com/cdbs/www-data/pdf/RDA0000/AOA0000C301.pdf"
			(at 132.08 207.01 0)
			(effects
				(font
					(size 1.27 1.27)
					(thickness 0.15)
				)
				(justify left bottom)
				(hide yes)
			)
		)
		(property "Description" ""
			(at 111.76 189.23 0)
			(effects
				(font
					(size 1.27 1.27)
				)
			)
		)
		(property "Manufacturer" "Panasonic"
			(at 132.08 212.09 0)
			(effects
				(font
					(size 1.27 1.27)
					(thickness 0.15)
				)
				(justify left bottom)
				(hide yes)
			)
		)
		(property "MPN" "ERJ2GE0R00X"
			(at 132.08 209.55 0)
			(effects
				(font
					(size 1.27 1.27)
					(thickness 0.15)
				)
				(justify left bottom)
				(hide yes)
			)
		)
		(property "Val" "0R"
			(at 110.49 187.96 0)
			(effects
				(font
					(size 1.27 1.27)
					(thickness 0.15)
				)
			)
		)
		(property "License" "Apache-2.0"
			(at 132.08 214.63 0)
			(effects
				(font
					(size 1.27 1.27)
					(thickness 0.15)
				)
				(justify left bottom)
				(hide yes)
			)
		)
		(property "Author" "Antmicro"
			(at 132.08 217.17 0)
			(effects
				(font
					(size 1.27 1.27)
					(thickness 0.15)
				)
				(justify left bottom)
				(hide yes)
			)
		)
		(property "Tolerance" "~"
			(at 132.08 199.39 0)
			(effects
				(font
					(size 1.27 1.27)
				)
				(justify left bottom)
				(hide yes)
			)
		)
		(property "Current" "1A"
			(at 132.08 219.71 0)
			(effects
				(font
					(size 1.27 1.27)
					(thickness 0.15)
				)
				(justify left bottom)
				(hide yes)
			)
		)
		(pin "1"
		)
		(pin "2"
		)
		(instances
			(project "k410t-devboard"
				(path ""
					(reference "R81")
					(unit 1)
				)
			)
		)
	)
	(symbol
		(lib_id "antmicroResistorNetworksArrays:R_4x33R_0201_array")
		(at 293.37 66.04 0)
		(unit 1)
		(exclude_from_sim no)
		(in_bom yes)
		(on_board yes)
		(dnp no)
		(property "Reference" "R61"
			(at 298.45 57.785 0)
			(effects
				(font
					(size 1.27 1.27)
				)
			)
		)
		(property "Value" "R_4x33R_0201_array"
			(at 298.45 59.69 0)
			(effects
				(font
					(size 1.27 1.27)
					(thickness 0.15)
				)
				(hide yes)
			)
		)
		(property "Footprint" "antmicro-footprints:R_Array_4x0201_Panasonic_EXB18V"
			(at 320.04 76.835 0)
			(effects
				(font
					(size 1.27 1.27)
					(thickness 0.15)
				)
				(justify left bottom)
				(hide yes)
			)
		)
		(property "Datasheet" "http://industrial.panasonic.com/cdbs/www-data/pdf/AOC0000/AOC0000C14.pdf"
			(at 320.04 79.375 0)
			(effects
				(font
					(size 1.27 1.27)
					(thickness 0.15)
				)
				(justify left bottom)
				(hide yes)
			)
		)
		(property "Description" ""
			(at 293.37 66.04 0)
			(effects
				(font
					(size 1.27 1.27)
				)
			)
		)
		(property "MPN" "EXB-18V330JX"
			(at 320.04 81.915 0)
			(effects
				(font
					(size 1.27 1.27)
					(thickness 0.15)
				)
				(justify left bottom)
				(hide yes)
			)
		)
		(property "Manufacturer" "Panasonic"
			(at 320.04 84.455 0)
			(effects
				(font
					(size 1.27 1.27)
					(thickness 0.15)
				)
				(justify left bottom)
				(hide yes)
			)
		)
		(property "Author" "Antmicro"
			(at 320.04 86.995 0)
			(effects
				(font
					(size 1.27 1.27)
					(thickness 0.15)
				)
				(justify left bottom)
				(hide yes)
			)
		)
		(property "License" "Apache-2.0"
			(at 320.04 89.535 0)
			(effects
				(font
					(size 1.27 1.27)
					(thickness 0.15)
				)
				(justify left bottom)
				(hide yes)
			)
		)
		(property "Val" "R_4x33R_0201"
			(at 298.45 62.865 0)
			(effects
				(font
					(size 1.27 1.27)
				)
			)
		)
		(pin "1"
		)
		(pin "2"
		)
		(pin "3"
		)
		(pin "4"
		)
		(pin "5"
		)
		(pin "6"
		)
		(pin "7"
		)
		(pin "8"
		)
		(instances
			(project "k410t-devboard"
				(path ""
					(reference "R61")
					(unit 1)
				)
			)
		)
	)
	(symbol
		(lib_id "antmicropower:+3.3V")
		(at 326.39 49.53 0)
		(unit 1)
		(exclude_from_sim no)
		(in_bom yes)
		(on_board yes)
		(dnp no)
		(fields_autoplaced yes)
		(property "Reference" "#PWR0124"
			(at 326.39 53.34 0)
			(effects
				(font
					(size 1.27 1.27)
				)
				(hide yes)
			)
		)
		(property "Value" "+3V3"
			(at 326.39 45.974 0)
			(effects
				(font
					(size 1.27 1.27)
				)
			)
		)
		(property "Footprint" ""
			(at 326.39 49.53 0)
			(effects
				(font
					(size 1.27 1.27)
				)
				(hide yes)
			)
		)
		(property "Datasheet" ""
			(at 326.39 49.53 0)
			(effects
				(font
					(size 1.27 1.27)
				)
				(hide yes)
			)
		)
		(property "Description" ""
			(at 326.39 49.53 0)
			(effects
				(font
					(size 1.27 1.27)
				)
			)
		)
		(pin "1"
		)
		(instances
			(project "k410t-devboard"
				(path ""
					(reference "#PWR0124")
					(unit 1)
				)
			)
		)
	)
	(symbol
		(lib_id "antmicropower:+3.3V")
		(at 226.06 64.77 0)
		(unit 1)
		(exclude_from_sim no)
		(in_bom yes)
		(on_board yes)
		(dnp no)
		(fields_autoplaced yes)
		(property "Reference" "#PWR0122"
			(at 226.06 68.58 0)
			(effects
				(font
					(size 1.27 1.27)
				)
				(hide yes)
			)
		)
		(property "Value" "+3V3"
			(at 226.06 61.214 0)
			(effects
				(font
					(size 1.27 1.27)
				)
			)
		)
		(property "Footprint" ""
			(at 226.06 64.77 0)
			(effects
				(font
					(size 1.27 1.27)
				)
				(hide yes)
			)
		)
		(property "Datasheet" ""
			(at 226.06 64.77 0)
			(effects
				(font
					(size 1.27 1.27)
				)
				(hide yes)
			)
		)
		(property "Description" ""
			(at 226.06 64.77 0)
			(effects
				(font
					(size 1.27 1.27)
				)
			)
		)
		(pin "1"
		)
		(instances
			(project "k410t-devboard"
				(path ""
					(reference "#PWR0122")
					(unit 1)
				)
			)
		)
	)
	(symbol
		(lib_id "antmicropower:GND")
		(at 340.36 90.17 0)
		(unit 1)
		(exclude_from_sim no)
		(in_bom yes)
		(on_board yes)
		(dnp no)
		(property "Reference" "#PWR0134"
			(at 340.36 96.52 0)
			(effects
				(font
					(size 1.27 1.27)
				)
				(hide yes)
			)
		)
		(property "Value" "GND"
			(at 340.36 93.98 0)
			(effects
				(font
					(size 1.27 1.27)
				)
			)
		)
		(property "Footprint" ""
			(at 349.25 97.79 0)
			(effects
				(font
					(size 1.27 1.27)
					(thickness 0.15)
				)
				(justify left bottom)
				(hide yes)
			)
		)
		(property "Datasheet" ""
			(at 349.25 102.87 0)
			(effects
				(font
					(size 1.27 1.27)
					(thickness 0.15)
				)
				(justify left bottom)
				(hide yes)
			)
		)
		(property "Description" ""
			(at 340.36 90.17 0)
			(effects
				(font
					(size 1.27 1.27)
				)
			)
		)
		(property "Author" "Antmicro"
			(at 349.25 97.79 0)
			(effects
				(font
					(size 1.27 1.27)
					(thickness 0.15)
				)
				(justify left bottom)
				(hide yes)
			)
		)
		(property "License" "Apache-2.0"
			(at 349.25 100.33 0)
			(effects
				(font
					(size 1.27 1.27)
					(thickness 0.15)
				)
				(justify left bottom)
				(hide yes)
			)
		)
		(pin "1"
		)
		(instances
			(project "k410t-devboard"
				(path ""
					(reference "#PWR0134")
					(unit 1)
				)
			)
		)
	)
	(symbol
		(lib_id "antmicroResistors0402:R_0R_0402")
		(at 110.49 76.2 0)
		(unit 1)
		(exclude_from_sim no)
		(in_bom yes)
		(on_board yes)
		(dnp no)
		(property "Reference" "R78"
			(at 117.475 74.93 0)
			(effects
				(font
					(size 1.27 1.27)
				)
			)
		)
		(property "Value" "R_0R_0402"
			(at 130.81 88.9 0)
			(effects
				(font
					(size 1.27 1.27)
					(thickness 0.15)
				)
				(justify left bottom)
				(hide yes)
			)
		)
		(property "Footprint" "antmicro-footprints:R_0402_1005Metric"
			(at 130.81 91.44 0)
			(effects
				(font
					(size 1.27 1.27)
					(thickness 0.15)
				)
				(justify left bottom)
				(hide yes)
			)
		)
		(property "Datasheet" "https://industrial.panasonic.com/cdbs/www-data/pdf/RDA0000/AOA0000C301.pdf"
			(at 130.81 93.98 0)
			(effects
				(font
					(size 1.27 1.27)
					(thickness 0.15)
				)
				(justify left bottom)
				(hide yes)
			)
		)
		(property "Description" ""
			(at 110.49 76.2 0)
			(effects
				(font
					(size 1.27 1.27)
				)
			)
		)
		(property "Manufacturer" "Panasonic"
			(at 130.81 99.06 0)
			(effects
				(font
					(size 1.27 1.27)
					(thickness 0.15)
				)
				(justify left bottom)
				(hide yes)
			)
		)
		(property "MPN" "ERJ2GE0R00X"
			(at 130.81 96.52 0)
			(effects
				(font
					(size 1.27 1.27)
					(thickness 0.15)
				)
				(justify left bottom)
				(hide yes)
			)
		)
		(property "Val" "0R"
			(at 109.22 74.93 0)
			(effects
				(font
					(size 1.27 1.27)
					(thickness 0.15)
				)
			)
		)
		(property "License" "Apache-2.0"
			(at 130.81 101.6 0)
			(effects
				(font
					(size 1.27 1.27)
					(thickness 0.15)
				)
				(justify left bottom)
				(hide yes)
			)
		)
		(property "Author" "Antmicro"
			(at 130.81 104.14 0)
			(effects
				(font
					(size 1.27 1.27)
					(thickness 0.15)
				)
				(justify left bottom)
				(hide yes)
			)
		)
		(property "Tolerance" "~"
			(at 130.81 86.36 0)
			(effects
				(font
					(size 1.27 1.27)
				)
				(justify left bottom)
				(hide yes)
			)
		)
		(property "Current" "1A"
			(at 130.81 106.68 0)
			(effects
				(font
					(size 1.27 1.27)
					(thickness 0.15)
				)
				(justify left bottom)
				(hide yes)
			)
		)
		(pin "1"
		)
		(pin "2"
		)
		(instances
			(project "k410t-devboard"
				(path ""
					(reference "R78")
					(unit 1)
				)
			)
		)
	)
	(symbol
		(lib_id "antmicroResistors0402:R_10k_0402")
		(at 287.02 181.61 90)
		(unit 1)
		(exclude_from_sim no)
		(in_bom yes)
		(on_board yes)
		(dnp no)
		(property "Reference" "R94"
			(at 288.29 177.8 90)
			(effects
				(font
					(size 1.27 1.27)
				)
				(justify right)
			)
		)
		(property "Value" "R_10k_0402"
			(at 299.72 161.29 0)
			(effects
				(font
					(size 1.27 1.27)
					(thickness 0.15)
				)
				(justify left bottom)
				(hide yes)
			)
		)
		(property "Footprint" "antmicro-footprints:R_0402_1005Metric"
			(at 302.26 161.29 0)
			(effects
				(font
					(size 1.27 1.27)
					(thickness 0.15)
				)
				(justify left bottom)
				(hide yes)
			)
		)
		(property "Datasheet" "https://www.bourns.com/docs/product-datasheets/cr.pdf"
			(at 304.8 161.29 0)
			(effects
				(font
					(size 1.27 1.27)
					(thickness 0.15)
				)
				(justify left bottom)
				(hide yes)
			)
		)
		(property "Description" ""
			(at 287.02 181.61 0)
			(effects
				(font
					(size 1.27 1.27)
				)
			)
		)
		(property "Manufacturer" "Bourns"
			(at 309.88 161.29 0)
			(effects
				(font
					(size 1.27 1.27)
					(thickness 0.15)
				)
				(justify left bottom)
				(hide yes)
			)
		)
		(property "MPN" "CR0402-FX-1002GLF"
			(at 307.34 161.29 0)
			(effects
				(font
					(size 1.27 1.27)
					(thickness 0.15)
				)
				(justify left bottom)
				(hide yes)
			)
		)
		(property "Val" "10k"
			(at 288.29 180.34 90)
			(effects
				(font
					(size 1.27 1.27)
					(thickness 0.15)
				)
				(justify right)
			)
		)
		(property "License" "Apache-2.0"
			(at 312.42 161.29 0)
			(effects
				(font
					(size 1.27 1.27)
					(thickness 0.15)
				)
				(justify left bottom)
				(hide yes)
			)
		)
		(property "Author" "Antmicro"
			(at 314.96 161.29 0)
			(effects
				(font
					(size 1.27 1.27)
					(thickness 0.15)
				)
				(justify left bottom)
				(hide yes)
			)
		)
		(property "Tolerance" "1%"
			(at 297.18 161.29 0)
			(effects
				(font
					(size 1.27 1.27)
				)
				(justify left bottom)
				(hide yes)
			)
		)
		(pin "1"
		)
		(pin "2"
		)
		(instances
			(project "k410t-devboard"
				(path ""
					(reference "R94")
					(unit 1)
				)
			)
		)
	)
	(symbol
		(lib_id "antmicroMemory:MT25QL256ABA1EW7-0SIT")
		(at 350.52 186.69 0)
		(unit 1)
		(exclude_from_sim no)
		(in_bom no)
		(on_board yes)
		(dnp yes)
		(fields_autoplaced yes)
		(property "Reference" "U14"
			(at 364.49 176.53 0)
			(effects
				(font
					(size 1.27 1.27)
				)
			)
		)
		(property "Value" "MT25QL256ABA1EW7-0SIT"
			(at 364.49 179.07 0)
			(effects
				(font
					(size 1.27 1.27)
					(thickness 0.15)
				)
			)
		)
		(property "Footprint" "antmicro-footprints:WDFN-8-1EP_6x5mm_P1.27mm_EP3.4x4mm"
			(at 392.43 194.31 0)
			(effects
				(font
					(size 1.27 1.27)
					(thickness 0.15)
				)
				(justify left bottom)
				(hide yes)
			)
		)
		(property "Datasheet" "https://www.micron.com/products/nor-flash/serial-nor-flash/part-catalog/mt25ql256aba1ew7-0sit"
			(at 392.43 196.85 0)
			(effects
				(font
					(size 1.27 1.27)
					(thickness 0.15)
				)
				(justify left bottom)
				(hide yes)
			)
		)
		(property "Description" ""
			(at 350.52 186.69 0)
			(effects
				(font
					(size 1.27 1.27)
				)
			)
		)
		(property "MPN" "MT25QL256ABA1EW7-0SIT"
			(at 392.43 199.39 0)
			(effects
				(font
					(size 1.27 1.27)
					(thickness 0.15)
				)
				(justify left bottom)
				(hide yes)
			)
		)
		(property "Manufacturer" "Micron Technology"
			(at 392.43 201.93 0)
			(effects
				(font
					(size 1.27 1.27)
					(thickness 0.15)
				)
				(justify left bottom)
				(hide yes)
			)
		)
		(property "Author" "Antmicro"
			(at 392.43 204.47 0)
			(effects
				(font
					(size 1.27 1.27)
					(thickness 0.15)
				)
				(justify left bottom)
				(hide yes)
			)
		)
		(property "License" "Apache-2.0"
			(at 392.43 207.01 0)
			(effects
				(font
					(size 1.27 1.27)
					(thickness 0.15)
				)
				(justify left bottom)
				(hide yes)
			)
		)
		(property "DNP" "DNP"
			(at 364.49 181.61 0)
			(effects
				(font
					(size 1.27 1.27)
				)
			)
		)
		(pin "1"
		)
		(pin "2"
		)
		(pin "3"
		)
		(pin "4"
		)
		(pin "5"
		)
		(pin "6"
		)
		(pin "7"
		)
		(pin "8"
		)
		(pin "9"
		)
		(instances
			(project "k410t-devboard"
				(path ""
					(reference "U14")
					(unit 1)
				)
			)
		)
	)
	(symbol
		(lib_id "antmicroResistors0402:R_10k_0402")
		(at 74.93 60.96 90)
		(unit 1)
		(exclude_from_sim no)
		(in_bom yes)
		(on_board yes)
		(dnp no)
		(property "Reference" "R64"
			(at 76.2 57.15 90)
			(effects
				(font
					(size 1.27 1.27)
				)
				(justify right)
			)
		)
		(property "Value" "R_10k_0402"
			(at 87.63 40.64 0)
			(effects
				(font
					(size 1.27 1.27)
					(thickness 0.15)
				)
				(justify left bottom)
				(hide yes)
			)
		)
		(property "Footprint" "antmicro-footprints:R_0402_1005Metric"
			(at 90.17 40.64 0)
			(effects
				(font
					(size 1.27 1.27)
					(thickness 0.15)
				)
				(justify left bottom)
				(hide yes)
			)
		)
		(property "Datasheet" "https://www.bourns.com/docs/product-datasheets/cr.pdf"
			(at 92.71 40.64 0)
			(effects
				(font
					(size 1.27 1.27)
					(thickness 0.15)
				)
				(justify left bottom)
				(hide yes)
			)
		)
		(property "Description" ""
			(at 74.93 60.96 0)
			(effects
				(font
					(size 1.27 1.27)
				)
			)
		)
		(property "Manufacturer" "Bourns"
			(at 97.79 40.64 0)
			(effects
				(font
					(size 1.27 1.27)
					(thickness 0.15)
				)
				(justify left bottom)
				(hide yes)
			)
		)
		(property "MPN" "CR0402-FX-1002GLF"
			(at 95.25 40.64 0)
			(effects
				(font
					(size 1.27 1.27)
					(thickness 0.15)
				)
				(justify left bottom)
				(hide yes)
			)
		)
		(property "Val" "10k"
			(at 76.2 59.69 90)
			(effects
				(font
					(size 1.27 1.27)
					(thickness 0.15)
				)
				(justify right)
			)
		)
		(property "License" "Apache-2.0"
			(at 100.33 40.64 0)
			(effects
				(font
					(size 1.27 1.27)
					(thickness 0.15)
				)
				(justify left bottom)
				(hide yes)
			)
		)
		(property "Author" "Antmicro"
			(at 102.87 40.64 0)
			(effects
				(font
					(size 1.27 1.27)
					(thickness 0.15)
				)
				(justify left bottom)
				(hide yes)
			)
		)
		(property "Tolerance" "1%"
			(at 85.09 40.64 0)
			(effects
				(font
					(size 1.27 1.27)
				)
				(justify left bottom)
				(hide yes)
			)
		)
		(pin "1"
		)
		(pin "2"
		)
		(instances
			(project "k410t-devboard"
				(path ""
					(reference "R64")
					(unit 1)
				)
			)
		)
	)
	(symbol
		(lib_id "antmicroResistors0402:R_0R_0402")
		(at 316.23 189.23 0)
		(unit 1)
		(exclude_from_sim no)
		(in_bom yes)
		(on_board yes)
		(dnp no)
		(property "Reference" "R100"
			(at 323.85 187.96 0)
			(effects
				(font
					(size 1.27 1.27)
				)
			)
		)
		(property "Value" "R_0R_0402"
			(at 336.55 201.93 0)
			(effects
				(font
					(size 1.27 1.27)
					(thickness 0.15)
				)
				(justify left bottom)
				(hide yes)
			)
		)
		(property "Footprint" "antmicro-footprints:R_0402_1005Metric"
			(at 336.55 204.47 0)
			(effects
				(font
					(size 1.27 1.27)
					(thickness 0.15)
				)
				(justify left bottom)
				(hide yes)
			)
		)
		(property "Datasheet" "https://industrial.panasonic.com/cdbs/www-data/pdf/RDA0000/AOA0000C301.pdf"
			(at 336.55 207.01 0)
			(effects
				(font
					(size 1.27 1.27)
					(thickness 0.15)
				)
				(justify left bottom)
				(hide yes)
			)
		)
		(property "Description" ""
			(at 316.23 189.23 0)
			(effects
				(font
					(size 1.27 1.27)
				)
			)
		)
		(property "Manufacturer" "Panasonic"
			(at 336.55 212.09 0)
			(effects
				(font
					(size 1.27 1.27)
					(thickness 0.15)
				)
				(justify left bottom)
				(hide yes)
			)
		)
		(property "MPN" "ERJ2GE0R00X"
			(at 336.55 209.55 0)
			(effects
				(font
					(size 1.27 1.27)
					(thickness 0.15)
				)
				(justify left bottom)
				(hide yes)
			)
		)
		(property "Val" "0R"
			(at 314.96 187.96 0)
			(effects
				(font
					(size 1.27 1.27)
					(thickness 0.15)
				)
			)
		)
		(property "License" "Apache-2.0"
			(at 336.55 214.63 0)
			(effects
				(font
					(size 1.27 1.27)
					(thickness 0.15)
				)
				(justify left bottom)
				(hide yes)
			)
		)
		(property "Author" "Antmicro"
			(at 336.55 217.17 0)
			(effects
				(font
					(size 1.27 1.27)
					(thickness 0.15)
				)
				(justify left bottom)
				(hide yes)
			)
		)
		(property "Tolerance" "~"
			(at 336.55 199.39 0)
			(effects
				(font
					(size 1.27 1.27)
				)
				(justify left bottom)
				(hide yes)
			)
		)
		(property "Current" "1A"
			(at 336.55 219.71 0)
			(effects
				(font
					(size 1.27 1.27)
					(thickness 0.15)
				)
				(justify left bottom)
				(hide yes)
			)
		)
		(pin "1"
		)
		(pin "2"
		)
		(instances
			(project "k410t-devboard"
				(path ""
					(reference "R100")
					(unit 1)
				)
			)
		)
	)
	(symbol
		(lib_id "antmicroResistors0402:R_10k_0402")
		(at 238.76 86.36 180)
		(unit 1)
		(exclude_from_sim no)
		(in_bom yes)
		(on_board yes)
		(dnp no)
		(property "Reference" "R92"
			(at 240.665 85.09 0)
			(effects
				(font
					(size 1.27 1.27)
				)
			)
		)
		(property "Value" "R_10k_0402"
			(at 218.44 73.66 0)
			(effects
				(font
					(size 1.27 1.27)
					(thickness 0.15)
				)
				(justify left bottom)
				(hide yes)
			)
		)
		(property "Footprint" "antmicro-footprints:R_0402_1005Metric"
			(at 218.44 71.12 0)
			(effects
				(font
					(size 1.27 1.27)
					(thickness 0.15)
				)
				(justify left bottom)
				(hide yes)
			)
		)
		(property "Datasheet" "https://www.bourns.com/docs/product-datasheets/cr.pdf"
			(at 218.44 68.58 0)
			(effects
				(font
					(size 1.27 1.27)
					(thickness 0.15)
				)
				(justify left bottom)
				(hide yes)
			)
		)
		(property "Description" ""
			(at 238.76 86.36 0)
			(effects
				(font
					(size 1.27 1.27)
				)
			)
		)
		(property "Manufacturer" "Bourns"
			(at 218.44 63.5 0)
			(effects
				(font
					(size 1.27 1.27)
					(thickness 0.15)
				)
				(justify left bottom)
				(hide yes)
			)
		)
		(property "MPN" "CR0402-FX-1002GLF"
			(at 218.44 66.04 0)
			(effects
				(font
					(size 1.27 1.27)
					(thickness 0.15)
				)
				(justify left bottom)
				(hide yes)
			)
		)
		(property "Val" "10k"
			(at 231.775 85.09 0)
			(effects
				(font
					(size 1.27 1.27)
					(thickness 0.15)
				)
			)
		)
		(property "License" "Apache-2.0"
			(at 218.44 60.96 0)
			(effects
				(font
					(size 1.27 1.27)
					(thickness 0.15)
				)
				(justify left bottom)
				(hide yes)
			)
		)
		(property "Author" "Antmicro"
			(at 218.44 58.42 0)
			(effects
				(font
					(size 1.27 1.27)
					(thickness 0.15)
				)
				(justify left bottom)
				(hide yes)
			)
		)
		(property "Tolerance" "1%"
			(at 218.44 76.2 0)
			(effects
				(font
					(size 1.27 1.27)
				)
				(justify left bottom)
				(hide yes)
			)
		)
		(pin "1"
		)
		(pin "2"
		)
		(instances
			(project "k410t-devboard"
				(path ""
					(reference "R92")
					(unit 1)
				)
			)
		)
	)
	(symbol
		(lib_id "antmicroResistors0402:R_10k_0402")
		(at 83.82 60.96 90)
		(unit 1)
		(exclude_from_sim no)
		(in_bom yes)
		(on_board yes)
		(dnp no)
		(property "Reference" "R66"
			(at 85.09 57.15 90)
			(effects
				(font
					(size 1.27 1.27)
				)
				(justify right)
			)
		)
		(property "Value" "R_10k_0402"
			(at 96.52 40.64 0)
			(effects
				(font
					(size 1.27 1.27)
					(thickness 0.15)
				)
				(justify left bottom)
				(hide yes)
			)
		)
		(property "Footprint" "antmicro-footprints:R_0402_1005Metric"
			(at 99.06 40.64 0)
			(effects
				(font
					(size 1.27 1.27)
					(thickness 0.15)
				)
				(justify left bottom)
				(hide yes)
			)
		)
		(property "Datasheet" "https://www.bourns.com/docs/product-datasheets/cr.pdf"
			(at 101.6 40.64 0)
			(effects
				(font
					(size 1.27 1.27)
					(thickness 0.15)
				)
				(justify left bottom)
				(hide yes)
			)
		)
		(property "Description" ""
			(at 83.82 60.96 0)
			(effects
				(font
					(size 1.27 1.27)
				)
			)
		)
		(property "Manufacturer" "Bourns"
			(at 106.68 40.64 0)
			(effects
				(font
					(size 1.27 1.27)
					(thickness 0.15)
				)
				(justify left bottom)
				(hide yes)
			)
		)
		(property "MPN" "CR0402-FX-1002GLF"
			(at 104.14 40.64 0)
			(effects
				(font
					(size 1.27 1.27)
					(thickness 0.15)
				)
				(justify left bottom)
				(hide yes)
			)
		)
		(property "Val" "10k"
			(at 85.09 59.69 90)
			(effects
				(font
					(size 1.27 1.27)
					(thickness 0.15)
				)
				(justify right)
			)
		)
		(property "License" "Apache-2.0"
			(at 109.22 40.64 0)
			(effects
				(font
					(size 1.27 1.27)
					(thickness 0.15)
				)
				(justify left bottom)
				(hide yes)
			)
		)
		(property "Author" "Antmicro"
			(at 111.76 40.64 0)
			(effects
				(font
					(size 1.27 1.27)
					(thickness 0.15)
				)
				(justify left bottom)
				(hide yes)
			)
		)
		(property "Tolerance" "1%"
			(at 93.98 40.64 0)
			(effects
				(font
					(size 1.27 1.27)
				)
				(justify left bottom)
				(hide yes)
			)
		)
		(pin "1"
		)
		(pin "2"
		)
		(instances
			(project "k410t-devboard"
				(path ""
					(reference "R66")
					(unit 1)
				)
			)
		)
	)
	(symbol
		(lib_id "antmicropower:GND")
		(at 175.26 200.66 0)
		(unit 1)
		(exclude_from_sim no)
		(in_bom yes)
		(on_board yes)
		(dnp no)
		(property "Reference" "#PWR0123"
			(at 175.26 207.01 0)
			(effects
				(font
					(size 1.27 1.27)
				)
				(hide yes)
			)
		)
		(property "Value" "GND"
			(at 175.26 204.47 0)
			(effects
				(font
					(size 1.27 1.27)
				)
			)
		)
		(property "Footprint" ""
			(at 184.15 208.28 0)
			(effects
				(font
					(size 1.27 1.27)
					(thickness 0.15)
				)
				(justify left bottom)
				(hide yes)
			)
		)
		(property "Datasheet" ""
			(at 184.15 213.36 0)
			(effects
				(font
					(size 1.27 1.27)
					(thickness 0.15)
				)
				(justify left bottom)
				(hide yes)
			)
		)
		(property "Description" ""
			(at 175.26 200.66 0)
			(effects
				(font
					(size 1.27 1.27)
				)
			)
		)
		(property "Author" "Antmicro"
			(at 184.15 208.28 0)
			(effects
				(font
					(size 1.27 1.27)
					(thickness 0.15)
				)
				(justify left bottom)
				(hide yes)
			)
		)
		(property "License" "Apache-2.0"
			(at 184.15 210.82 0)
			(effects
				(font
					(size 1.27 1.27)
					(thickness 0.15)
				)
				(justify left bottom)
				(hide yes)
			)
		)
		(pin "1"
		)
		(instances
			(project "k410t-devboard"
				(path ""
					(reference "#PWR0123")
					(unit 1)
				)
			)
		)
	)
	(symbol
		(lib_id "antmicroResistors0402:R_100R_0402")
		(at 304.8 208.28 90)
		(unit 1)
		(exclude_from_sim no)
		(in_bom no)
		(on_board yes)
		(dnp yes)
		(property "Reference" "R97"
			(at 306.07 204.47 90)
			(effects
				(font
					(size 1.27 1.27)
				)
				(justify right)
			)
		)
		(property "Value" "R_100R_0402"
			(at 317.5 187.96 0)
			(effects
				(font
					(size 1.27 1.27)
					(thickness 0.15)
				)
				(justify left bottom)
				(hide yes)
			)
		)
		(property "Footprint" "antmicro-footprints:R_0402_1005Metric"
			(at 320.04 187.96 0)
			(effects
				(font
					(size 1.27 1.27)
					(thickness 0.15)
				)
				(justify left bottom)
				(hide yes)
			)
		)
		(property "Datasheet" "https://www.bourns.com/docs/product-datasheets/cr.pdf"
			(at 322.58 187.96 0)
			(effects
				(font
					(size 1.27 1.27)
					(thickness 0.15)
				)
				(justify left bottom)
				(hide yes)
			)
		)
		(property "Description" ""
			(at 304.8 208.28 0)
			(effects
				(font
					(size 1.27 1.27)
				)
			)
		)
		(property "Manufacturer" "Bourns"
			(at 327.66 187.96 0)
			(effects
				(font
					(size 1.27 1.27)
					(thickness 0.15)
				)
				(justify left bottom)
				(hide yes)
			)
		)
		(property "MPN" "CR0402-FX-1000GLF"
			(at 325.12 187.96 0)
			(effects
				(font
					(size 1.27 1.27)
					(thickness 0.15)
				)
				(justify left bottom)
				(hide yes)
			)
		)
		(property "Val" "100R"
			(at 306.07 207.01 90)
			(effects
				(font
					(size 1.27 1.27)
					(thickness 0.15)
				)
				(justify right)
			)
		)
		(property "DNP" "DNP"
			(at 304.8 203.835 0)
			(effects
				(font
					(size 1.27 1.27)
				)
				(justify right)
			)
		)
		(property "License" "Apache-2.0"
			(at 330.2 187.96 0)
			(effects
				(font
					(size 1.27 1.27)
					(thickness 0.15)
				)
				(justify left bottom)
				(hide yes)
			)
		)
		(property "Author" "Antmicro"
			(at 332.74 187.96 0)
			(effects
				(font
					(size 1.27 1.27)
					(thickness 0.15)
				)
				(justify left bottom)
				(hide yes)
			)
		)
		(property "Tolerance" "1%"
			(at 314.96 187.96 0)
			(effects
				(font
					(size 1.27 1.27)
				)
				(justify left bottom)
				(hide yes)
			)
		)
		(pin "1"
		)
		(pin "2"
		)
		(instances
			(project "k410t-devboard"
				(path ""
					(reference "R97")
					(unit 1)
				)
			)
		)
	)
	(symbol
		(lib_id "antmicropower:+3.3V")
		(at 182.88 64.77 0)
		(unit 1)
		(exclude_from_sim no)
		(in_bom yes)
		(on_board yes)
		(dnp no)
		(fields_autoplaced yes)
		(property "Reference" "#PWR0120"
			(at 182.88 68.58 0)
			(effects
				(font
					(size 1.27 1.27)
				)
				(hide yes)
			)
		)
		(property "Value" "+3V3"
			(at 182.88 61.214 0)
			(effects
				(font
					(size 1.27 1.27)
				)
			)
		)
		(property "Footprint" ""
			(at 182.88 64.77 0)
			(effects
				(font
					(size 1.27 1.27)
				)
				(hide yes)
			)
		)
		(property "Datasheet" ""
			(at 182.88 64.77 0)
			(effects
				(font
					(size 1.27 1.27)
				)
				(hide yes)
			)
		)
		(property "Description" ""
			(at 182.88 64.77 0)
			(effects
				(font
					(size 1.27 1.27)
				)
			)
		)
		(pin "1"
		)
		(instances
			(project "k410t-devboard"
				(path ""
					(reference "#PWR0120")
					(unit 1)
				)
			)
		)
	)
	(symbol
		(lib_id "antmicroResistors0402:R_100R_0402")
		(at 101.6 181.61 90)
		(unit 1)
		(exclude_from_sim no)
		(in_bom no)
		(on_board yes)
		(dnp yes)
		(property "Reference" "R72"
			(at 102.87 177.8 90)
			(effects
				(font
					(size 1.27 1.27)
				)
				(justify right)
			)
		)
		(property "Value" "R_100R_0402"
			(at 114.3 161.29 0)
			(effects
				(font
					(size 1.27 1.27)
					(thickness 0.15)
				)
				(justify left bottom)
				(hide yes)
			)
		)
		(property "Footprint" "antmicro-footprints:R_0402_1005Metric"
			(at 116.84 161.29 0)
			(effects
				(font
					(size 1.27 1.27)
					(thickness 0.15)
				)
				(justify left bottom)
				(hide yes)
			)
		)
		(property "Datasheet" "https://www.bourns.com/docs/product-datasheets/cr.pdf"
			(at 119.38 161.29 0)
			(effects
				(font
					(size 1.27 1.27)
					(thickness 0.15)
				)
				(justify left bottom)
				(hide yes)
			)
		)
		(property "Description" ""
			(at 101.6 181.61 0)
			(effects
				(font
					(size 1.27 1.27)
				)
			)
		)
		(property "Manufacturer" "Bourns"
			(at 124.46 161.29 0)
			(effects
				(font
					(size 1.27 1.27)
					(thickness 0.15)
				)
				(justify left bottom)
				(hide yes)
			)
		)
		(property "MPN" "CR0402-FX-1000GLF"
			(at 121.92 161.29 0)
			(effects
				(font
					(size 1.27 1.27)
					(thickness 0.15)
				)
				(justify left bottom)
				(hide yes)
			)
		)
		(property "Val" "100R"
			(at 102.87 180.34 90)
			(effects
				(font
					(size 1.27 1.27)
					(thickness 0.15)
				)
				(justify right)
			)
		)
		(property "License" "Apache-2.0"
			(at 127 161.29 0)
			(effects
				(font
					(size 1.27 1.27)
					(thickness 0.15)
				)
				(justify left bottom)
				(hide yes)
			)
		)
		(property "Author" "Antmicro"
			(at 129.54 161.29 0)
			(effects
				(font
					(size 1.27 1.27)
					(thickness 0.15)
				)
				(justify left bottom)
				(hide yes)
			)
		)
		(property "Tolerance" "1%"
			(at 111.76 161.29 0)
			(effects
				(font
					(size 1.27 1.27)
				)
				(justify left bottom)
				(hide yes)
			)
		)
		(property "DNP" "DNP"
			(at 101.6 179.07 0)
			(effects
				(font
					(size 1.27 1.27)
				)
			)
		)
		(pin "1"
		)
		(pin "2"
		)
		(instances
			(project "k410t-devboard"
				(path ""
					(reference "R72")
					(unit 1)
				)
			)
		)
	)
	(symbol
		(lib_id "antmicropower:VCC_USR_B")
		(at 278.13 172.72 0)
		(mirror y)
		(unit 1)
		(exclude_from_sim no)
		(in_bom yes)
		(on_board yes)
		(dnp no)
		(fields_autoplaced yes)
		(property "Reference" "#PWR0443"
			(at 278.13 176.53 0)
			(effects
				(font
					(size 1.27 1.27)
				)
				(hide yes)
			)
		)
		(property "Value" "VCC_USR_B"
			(at 278.13 168.91 0)
			(effects
				(font
					(size 1.27 1.27)
				)
			)
		)
		(property "Footprint" ""
			(at 278.13 172.72 0)
			(effects
				(font
					(size 1.27 1.27)
				)
				(hide yes)
			)
		)
		(property "Datasheet" ""
			(at 278.13 172.72 0)
			(effects
				(font
					(size 1.27 1.27)
				)
				(hide yes)
			)
		)
		(property "Description" ""
			(at 278.13 172.72 0)
			(effects
				(font
					(size 1.27 1.27)
				)
			)
		)
		(pin "1"
		)
		(instances
			(project "k410t-devboard"
				(path ""
					(reference "#PWR0443")
					(unit 1)
				)
			)
		)
	)
	(symbol
		(lib_id "antmicroResistors0402:R_10k_0402")
		(at 278.13 181.61 90)
		(unit 1)
		(exclude_from_sim no)
		(in_bom yes)
		(on_board yes)
		(dnp no)
		(property "Reference" "R93"
			(at 279.4 177.8 90)
			(effects
				(font
					(size 1.27 1.27)
				)
				(justify right)
			)
		)
		(property "Value" "R_10k_0402"
			(at 290.83 161.29 0)
			(effects
				(font
					(size 1.27 1.27)
					(thickness 0.15)
				)
				(justify left bottom)
				(hide yes)
			)
		)
		(property "Footprint" "antmicro-footprints:R_0402_1005Metric"
			(at 293.37 161.29 0)
			(effects
				(font
					(size 1.27 1.27)
					(thickness 0.15)
				)
				(justify left bottom)
				(hide yes)
			)
		)
		(property "Datasheet" "https://www.bourns.com/docs/product-datasheets/cr.pdf"
			(at 295.91 161.29 0)
			(effects
				(font
					(size 1.27 1.27)
					(thickness 0.15)
				)
				(justify left bottom)
				(hide yes)
			)
		)
		(property "Description" ""
			(at 278.13 181.61 0)
			(effects
				(font
					(size 1.27 1.27)
				)
			)
		)
		(property "Manufacturer" "Bourns"
			(at 300.99 161.29 0)
			(effects
				(font
					(size 1.27 1.27)
					(thickness 0.15)
				)
				(justify left bottom)
				(hide yes)
			)
		)
		(property "MPN" "CR0402-FX-1002GLF"
			(at 298.45 161.29 0)
			(effects
				(font
					(size 1.27 1.27)
					(thickness 0.15)
				)
				(justify left bottom)
				(hide yes)
			)
		)
		(property "Val" "10k"
			(at 279.4 180.34 90)
			(effects
				(font
					(size 1.27 1.27)
					(thickness 0.15)
				)
				(justify right)
			)
		)
		(property "License" "Apache-2.0"
			(at 303.53 161.29 0)
			(effects
				(font
					(size 1.27 1.27)
					(thickness 0.15)
				)
				(justify left bottom)
				(hide yes)
			)
		)
		(property "Author" "Antmicro"
			(at 306.07 161.29 0)
			(effects
				(font
					(size 1.27 1.27)
					(thickness 0.15)
				)
				(justify left bottom)
				(hide yes)
			)
		)
		(property "Tolerance" "1%"
			(at 288.29 161.29 0)
			(effects
				(font
					(size 1.27 1.27)
				)
				(justify left bottom)
				(hide yes)
			)
		)
		(pin "1"
		)
		(pin "2"
		)
		(instances
			(project "k410t-devboard"
				(path ""
					(reference "R93")
					(unit 1)
				)
			)
		)
	)
	(symbol
		(lib_id "antmicroResistors0402:R_0R_0402")
		(at 110.49 66.04 0)
		(unit 1)
		(exclude_from_sim no)
		(in_bom yes)
		(on_board yes)
		(dnp no)
		(property "Reference" "R74"
			(at 117.475 64.77 0)
			(effects
				(font
					(size 1.27 1.27)
				)
			)
		)
		(property "Value" "R_0R_0402"
			(at 130.81 78.74 0)
			(effects
				(font
					(size 1.27 1.27)
					(thickness 0.15)
				)
				(justify left bottom)
				(hide yes)
			)
		)
		(property "Footprint" "antmicro-footprints:R_0402_1005Metric"
			(at 130.81 81.28 0)
			(effects
				(font
					(size 1.27 1.27)
					(thickness 0.15)
				)
				(justify left bottom)
				(hide yes)
			)
		)
		(property "Datasheet" "https://industrial.panasonic.com/cdbs/www-data/pdf/RDA0000/AOA0000C301.pdf"
			(at 130.81 83.82 0)
			(effects
				(font
					(size 1.27 1.27)
					(thickness 0.15)
				)
				(justify left bottom)
				(hide yes)
			)
		)
		(property "Description" ""
			(at 110.49 66.04 0)
			(effects
				(font
					(size 1.27 1.27)
				)
			)
		)
		(property "Manufacturer" "Panasonic"
			(at 130.81 88.9 0)
			(effects
				(font
					(size 1.27 1.27)
					(thickness 0.15)
				)
				(justify left bottom)
				(hide yes)
			)
		)
		(property "MPN" "ERJ2GE0R00X"
			(at 130.81 86.36 0)
			(effects
				(font
					(size 1.27 1.27)
					(thickness 0.15)
				)
				(justify left bottom)
				(hide yes)
			)
		)
		(property "Val" "0R"
			(at 109.22 64.77 0)
			(effects
				(font
					(size 1.27 1.27)
					(thickness 0.15)
				)
			)
		)
		(property "License" "Apache-2.0"
			(at 130.81 91.44 0)
			(effects
				(font
					(size 1.27 1.27)
					(thickness 0.15)
				)
				(justify left bottom)
				(hide yes)
			)
		)
		(property "Author" "Antmicro"
			(at 130.81 93.98 0)
			(effects
				(font
					(size 1.27 1.27)
					(thickness 0.15)
				)
				(justify left bottom)
				(hide yes)
			)
		)
		(property "Tolerance" "~"
			(at 130.81 76.2 0)
			(effects
				(font
					(size 1.27 1.27)
				)
				(justify left bottom)
				(hide yes)
			)
		)
		(property "Current" "1A"
			(at 130.81 96.52 0)
			(effects
				(font
					(size 1.27 1.27)
					(thickness 0.15)
				)
				(justify left bottom)
				(hide yes)
			)
		)
		(pin "1"
		)
		(pin "2"
		)
		(instances
			(project "k410t-devboard"
				(path ""
					(reference "R74")
					(unit 1)
				)
			)
		)
	)
	(symbol
		(lib_id "antmicroResistors0402:R_0R_0402")
		(at 111.76 191.77 0)
		(unit 1)
		(exclude_from_sim no)
		(in_bom yes)
		(on_board yes)
		(dnp no)
		(property "Reference" "R82"
			(at 118.745 190.5 0)
			(effects
				(font
					(size 1.27 1.27)
				)
			)
		)
		(property "Value" "R_0R_0402"
			(at 132.08 204.47 0)
			(effects
				(font
					(size 1.27 1.27)
					(thickness 0.15)
				)
				(justify left bottom)
				(hide yes)
			)
		)
		(property "Footprint" "antmicro-footprints:R_0402_1005Metric"
			(at 132.08 207.01 0)
			(effects
				(font
					(size 1.27 1.27)
					(thickness 0.15)
				)
				(justify left bottom)
				(hide yes)
			)
		)
		(property "Datasheet" "https://industrial.panasonic.com/cdbs/www-data/pdf/RDA0000/AOA0000C301.pdf"
			(at 132.08 209.55 0)
			(effects
				(font
					(size 1.27 1.27)
					(thickness 0.15)
				)
				(justify left bottom)
				(hide yes)
			)
		)
		(property "Description" ""
			(at 111.76 191.77 0)
			(effects
				(font
					(size 1.27 1.27)
				)
			)
		)
		(property "Manufacturer" "Panasonic"
			(at 132.08 214.63 0)
			(effects
				(font
					(size 1.27 1.27)
					(thickness 0.15)
				)
				(justify left bottom)
				(hide yes)
			)
		)
		(property "MPN" "ERJ2GE0R00X"
			(at 132.08 212.09 0)
			(effects
				(font
					(size 1.27 1.27)
					(thickness 0.15)
				)
				(justify left bottom)
				(hide yes)
			)
		)
		(property "Val" "0R"
			(at 110.49 190.5 0)
			(effects
				(font
					(size 1.27 1.27)
					(thickness 0.15)
				)
			)
		)
		(property "License" "Apache-2.0"
			(at 132.08 217.17 0)
			(effects
				(font
					(size 1.27 1.27)
					(thickness 0.15)
				)
				(justify left bottom)
				(hide yes)
			)
		)
		(property "Author" "Antmicro"
			(at 132.08 219.71 0)
			(effects
				(font
					(size 1.27 1.27)
					(thickness 0.15)
				)
				(justify left bottom)
				(hide yes)
			)
		)
		(property "Tolerance" "~"
			(at 132.08 201.93 0)
			(effects
				(font
					(size 1.27 1.27)
				)
				(justify left bottom)
				(hide yes)
			)
		)
		(property "Current" "1A"
			(at 132.08 222.25 0)
			(effects
				(font
					(size 1.27 1.27)
					(thickness 0.15)
				)
				(justify left bottom)
				(hide yes)
			)
		)
		(pin "1"
		)
		(pin "2"
		)
		(instances
			(project "k410t-devboard"
				(path ""
					(reference "R82")
					(unit 1)
				)
			)
		)
	)
	(symbol
		(lib_id "antmicroResistors0402:R_0R_0402")
		(at 111.76 196.85 0)
		(unit 1)
		(exclude_from_sim no)
		(in_bom yes)
		(on_board yes)
		(dnp no)
		(property "Reference" "R84"
			(at 118.745 195.58 0)
			(effects
				(font
					(size 1.27 1.27)
				)
			)
		)
		(property "Value" "R_0R_0402"
			(at 132.08 209.55 0)
			(effects
				(font
					(size 1.27 1.27)
					(thickness 0.15)
				)
				(justify left bottom)
				(hide yes)
			)
		)
		(property "Footprint" "antmicro-footprints:R_0402_1005Metric"
			(at 132.08 212.09 0)
			(effects
				(font
					(size 1.27 1.27)
					(thickness 0.15)
				)
				(justify left bottom)
				(hide yes)
			)
		)
		(property "Datasheet" "https://industrial.panasonic.com/cdbs/www-data/pdf/RDA0000/AOA0000C301.pdf"
			(at 132.08 214.63 0)
			(effects
				(font
					(size 1.27 1.27)
					(thickness 0.15)
				)
				(justify left bottom)
				(hide yes)
			)
		)
		(property "Description" ""
			(at 111.76 196.85 0)
			(effects
				(font
					(size 1.27 1.27)
				)
			)
		)
		(property "Manufacturer" "Panasonic"
			(at 132.08 219.71 0)
			(effects
				(font
					(size 1.27 1.27)
					(thickness 0.15)
				)
				(justify left bottom)
				(hide yes)
			)
		)
		(property "MPN" "ERJ2GE0R00X"
			(at 132.08 217.17 0)
			(effects
				(font
					(size 1.27 1.27)
					(thickness 0.15)
				)
				(justify left bottom)
				(hide yes)
			)
		)
		(property "Val" "0R"
			(at 110.49 195.58 0)
			(effects
				(font
					(size 1.27 1.27)
					(thickness 0.15)
				)
			)
		)
		(property "License" "Apache-2.0"
			(at 132.08 222.25 0)
			(effects
				(font
					(size 1.27 1.27)
					(thickness 0.15)
				)
				(justify left bottom)
				(hide yes)
			)
		)
		(property "Author" "Antmicro"
			(at 132.08 224.79 0)
			(effects
				(font
					(size 1.27 1.27)
					(thickness 0.15)
				)
				(justify left bottom)
				(hide yes)
			)
		)
		(property "Tolerance" "~"
			(at 132.08 207.01 0)
			(effects
				(font
					(size 1.27 1.27)
				)
				(justify left bottom)
				(hide yes)
			)
		)
		(property "Current" "1A"
			(at 132.08 227.33 0)
			(effects
				(font
					(size 1.27 1.27)
					(thickness 0.15)
				)
				(justify left bottom)
				(hide yes)
			)
		)
		(pin "1"
		)
		(pin "2"
		)
		(instances
			(project "k410t-devboard"
				(path ""
					(reference "R84")
					(unit 1)
				)
			)
		)
	)
	(symbol
		(lib_id "antmicroResistors0402:R_100R_0402")
		(at 101.6 60.96 90)
		(unit 1)
		(exclude_from_sim no)
		(in_bom no)
		(on_board yes)
		(dnp yes)
		(property "Reference" "R70"
			(at 102.87 57.15 90)
			(effects
				(font
					(size 1.27 1.27)
				)
				(justify right)
			)
		)
		(property "Value" "R_100R_0402"
			(at 114.3 40.64 0)
			(effects
				(font
					(size 1.27 1.27)
					(thickness 0.15)
				)
				(justify left bottom)
				(hide yes)
			)
		)
		(property "Footprint" "antmicro-footprints:R_0402_1005Metric"
			(at 116.84 40.64 0)
			(effects
				(font
					(size 1.27 1.27)
					(thickness 0.15)
				)
				(justify left bottom)
				(hide yes)
			)
		)
		(property "Datasheet" "https://www.bourns.com/docs/product-datasheets/cr.pdf"
			(at 119.38 40.64 0)
			(effects
				(font
					(size 1.27 1.27)
					(thickness 0.15)
				)
				(justify left bottom)
				(hide yes)
			)
		)
		(property "Description" ""
			(at 101.6 60.96 0)
			(effects
				(font
					(size 1.27 1.27)
				)
			)
		)
		(property "Manufacturer" "Bourns"
			(at 124.46 40.64 0)
			(effects
				(font
					(size 1.27 1.27)
					(thickness 0.15)
				)
				(justify left bottom)
				(hide yes)
			)
		)
		(property "MPN" "CR0402-FX-1000GLF"
			(at 121.92 40.64 0)
			(effects
				(font
					(size 1.27 1.27)
					(thickness 0.15)
				)
				(justify left bottom)
				(hide yes)
			)
		)
		(property "Val" "100R"
			(at 102.87 59.69 90)
			(effects
				(font
					(size 1.27 1.27)
					(thickness 0.15)
				)
				(justify right)
			)
		)
		(property "DNP" "DNP"
			(at 101.6 56.515 0)
			(effects
				(font
					(size 1.27 1.27)
				)
				(justify right)
			)
		)
		(property "License" "Apache-2.0"
			(at 127 40.64 0)
			(effects
				(font
					(size 1.27 1.27)
					(thickness 0.15)
				)
				(justify left bottom)
				(hide yes)
			)
		)
		(property "Author" "Antmicro"
			(at 129.54 40.64 0)
			(effects
				(font
					(size 1.27 1.27)
					(thickness 0.15)
				)
				(justify left bottom)
				(hide yes)
			)
		)
		(property "Tolerance" "1%"
			(at 111.76 40.64 0)
			(effects
				(font
					(size 1.27 1.27)
				)
				(justify left bottom)
				(hide yes)
			)
		)
		(pin "1"
		)
		(pin "2"
		)
		(instances
			(project "k410t-devboard"
				(path ""
					(reference "R70")
					(unit 1)
				)
			)
		)
	)
	(symbol
		(lib_id "antmicroResistors0402:R_0R_0402")
		(at 316.23 199.39 0)
		(unit 1)
		(exclude_from_sim no)
		(in_bom yes)
		(on_board yes)
		(dnp no)
		(property "Reference" "R104"
			(at 323.85 198.12 0)
			(effects
				(font
					(size 1.27 1.27)
				)
			)
		)
		(property "Value" "R_0R_0402"
			(at 336.55 212.09 0)
			(effects
				(font
					(size 1.27 1.27)
					(thickness 0.15)
				)
				(justify left bottom)
				(hide yes)
			)
		)
		(property "Footprint" "antmicro-footprints:R_0402_1005Metric"
			(at 336.55 214.63 0)
			(effects
				(font
					(size 1.27 1.27)
					(thickness 0.15)
				)
				(justify left bottom)
				(hide yes)
			)
		)
		(property "Datasheet" "https://industrial.panasonic.com/cdbs/www-data/pdf/RDA0000/AOA0000C301.pdf"
			(at 336.55 217.17 0)
			(effects
				(font
					(size 1.27 1.27)
					(thickness 0.15)
				)
				(justify left bottom)
				(hide yes)
			)
		)
		(property "Description" ""
			(at 316.23 199.39 0)
			(effects
				(font
					(size 1.27 1.27)
				)
			)
		)
		(property "Manufacturer" "Panasonic"
			(at 336.55 222.25 0)
			(effects
				(font
					(size 1.27 1.27)
					(thickness 0.15)
				)
				(justify left bottom)
				(hide yes)
			)
		)
		(property "MPN" "ERJ2GE0R00X"
			(at 336.55 219.71 0)
			(effects
				(font
					(size 1.27 1.27)
					(thickness 0.15)
				)
				(justify left bottom)
				(hide yes)
			)
		)
		(property "Val" "0R"
			(at 314.96 198.12 0)
			(effects
				(font
					(size 1.27 1.27)
					(thickness 0.15)
				)
			)
		)
		(property "License" "Apache-2.0"
			(at 336.55 224.79 0)
			(effects
				(font
					(size 1.27 1.27)
					(thickness 0.15)
				)
				(justify left bottom)
				(hide yes)
			)
		)
		(property "Author" "Antmicro"
			(at 336.55 227.33 0)
			(effects
				(font
					(size 1.27 1.27)
					(thickness 0.15)
				)
				(justify left bottom)
				(hide yes)
			)
		)
		(property "Tolerance" "~"
			(at 336.55 209.55 0)
			(effects
				(font
					(size 1.27 1.27)
				)
				(justify left bottom)
				(hide yes)
			)
		)
		(property "Current" "1A"
			(at 336.55 229.87 0)
			(effects
				(font
					(size 1.27 1.27)
					(thickness 0.15)
				)
				(justify left bottom)
				(hide yes)
			)
		)
		(pin "1"
		)
		(pin "2"
		)
		(instances
			(project "k410t-devboard"
				(path ""
					(reference "R104")
					(unit 1)
				)
			)
		)
	)
	(symbol
		(lib_id "antmicropower:GND")
		(at 101.6 209.55 0)
		(unit 1)
		(exclude_from_sim no)
		(in_bom yes)
		(on_board yes)
		(dnp no)
		(property "Reference" "#PWR0119"
			(at 101.6 215.9 0)
			(effects
				(font
					(size 1.27 1.27)
				)
				(hide yes)
			)
		)
		(property "Value" "GND"
			(at 101.6 213.36 0)
			(effects
				(font
					(size 1.27 1.27)
				)
			)
		)
		(property "Footprint" ""
			(at 110.49 217.17 0)
			(effects
				(font
					(size 1.27 1.27)
					(thickness 0.15)
				)
				(justify left bottom)
				(hide yes)
			)
		)
		(property "Datasheet" ""
			(at 110.49 222.25 0)
			(effects
				(font
					(size 1.27 1.27)
					(thickness 0.15)
				)
				(justify left bottom)
				(hide yes)
			)
		)
		(property "Description" ""
			(at 101.6 209.55 0)
			(effects
				(font
					(size 1.27 1.27)
				)
			)
		)
		(property "Author" "Antmicro"
			(at 110.49 217.17 0)
			(effects
				(font
					(size 1.27 1.27)
					(thickness 0.15)
				)
				(justify left bottom)
				(hide yes)
			)
		)
		(property "License" "Apache-2.0"
			(at 110.49 219.71 0)
			(effects
				(font
					(size 1.27 1.27)
					(thickness 0.15)
				)
				(justify left bottom)
				(hide yes)
			)
		)
		(pin "1"
		)
		(instances
			(project "k410t-devboard"
				(path ""
					(reference "#PWR0119")
					(unit 1)
				)
			)
		)
	)
	(symbol
		(lib_id "antmicroResistors0402:R_0R_0402")
		(at 110.49 73.66 0)
		(unit 1)
		(exclude_from_sim no)
		(in_bom yes)
		(on_board yes)
		(dnp no)
		(property "Reference" "R77"
			(at 117.475 72.39 0)
			(effects
				(font
					(size 1.27 1.27)
				)
			)
		)
		(property "Value" "R_0R_0402"
			(at 130.81 86.36 0)
			(effects
				(font
					(size 1.27 1.27)
					(thickness 0.15)
				)
				(justify left bottom)
				(hide yes)
			)
		)
		(property "Footprint" "antmicro-footprints:R_0402_1005Metric"
			(at 130.81 88.9 0)
			(effects
				(font
					(size 1.27 1.27)
					(thickness 0.15)
				)
				(justify left bottom)
				(hide yes)
			)
		)
		(property "Datasheet" "https://industrial.panasonic.com/cdbs/www-data/pdf/RDA0000/AOA0000C301.pdf"
			(at 130.81 91.44 0)
			(effects
				(font
					(size 1.27 1.27)
					(thickness 0.15)
				)
				(justify left bottom)
				(hide yes)
			)
		)
		(property "Description" ""
			(at 110.49 73.66 0)
			(effects
				(font
					(size 1.27 1.27)
				)
			)
		)
		(property "Manufacturer" "Panasonic"
			(at 130.81 96.52 0)
			(effects
				(font
					(size 1.27 1.27)
					(thickness 0.15)
				)
				(justify left bottom)
				(hide yes)
			)
		)
		(property "MPN" "ERJ2GE0R00X"
			(at 130.81 93.98 0)
			(effects
				(font
					(size 1.27 1.27)
					(thickness 0.15)
				)
				(justify left bottom)
				(hide yes)
			)
		)
		(property "Val" "0R"
			(at 109.22 72.39 0)
			(effects
				(font
					(size 1.27 1.27)
					(thickness 0.15)
				)
			)
		)
		(property "License" "Apache-2.0"
			(at 130.81 99.06 0)
			(effects
				(font
					(size 1.27 1.27)
					(thickness 0.15)
				)
				(justify left bottom)
				(hide yes)
			)
		)
		(property "Author" "Antmicro"
			(at 130.81 101.6 0)
			(effects
				(font
					(size 1.27 1.27)
					(thickness 0.15)
				)
				(justify left bottom)
				(hide yes)
			)
		)
		(property "Tolerance" "~"
			(at 130.81 83.82 0)
			(effects
				(font
					(size 1.27 1.27)
				)
				(justify left bottom)
				(hide yes)
			)
		)
		(property "Current" "1A"
			(at 130.81 104.14 0)
			(effects
				(font
					(size 1.27 1.27)
					(thickness 0.15)
				)
				(justify left bottom)
				(hide yes)
			)
		)
		(pin "1"
		)
		(pin "2"
		)
		(instances
			(project "k410t-devboard"
				(path ""
					(reference "R77")
					(unit 1)
				)
			)
		)
	)
	(symbol
		(lib_id "antmicroResistors0402:R_0R_0402")
		(at 111.76 194.31 0)
		(unit 1)
		(exclude_from_sim no)
		(in_bom yes)
		(on_board yes)
		(dnp no)
		(property "Reference" "R83"
			(at 118.745 193.04 0)
			(effects
				(font
					(size 1.27 1.27)
				)
			)
		)
		(property "Value" "R_0R_0402"
			(at 132.08 207.01 0)
			(effects
				(font
					(size 1.27 1.27)
					(thickness 0.15)
				)
				(justify left bottom)
				(hide yes)
			)
		)
		(property "Footprint" "antmicro-footprints:R_0402_1005Metric"
			(at 132.08 209.55 0)
			(effects
				(font
					(size 1.27 1.27)
					(thickness 0.15)
				)
				(justify left bottom)
				(hide yes)
			)
		)
		(property "Datasheet" "https://industrial.panasonic.com/cdbs/www-data/pdf/RDA0000/AOA0000C301.pdf"
			(at 132.08 212.09 0)
			(effects
				(font
					(size 1.27 1.27)
					(thickness 0.15)
				)
				(justify left bottom)
				(hide yes)
			)
		)
		(property "Description" ""
			(at 111.76 194.31 0)
			(effects
				(font
					(size 1.27 1.27)
				)
			)
		)
		(property "Manufacturer" "Panasonic"
			(at 132.08 217.17 0)
			(effects
				(font
					(size 1.27 1.27)
					(thickness 0.15)
				)
				(justify left bottom)
				(hide yes)
			)
		)
		(property "MPN" "ERJ2GE0R00X"
			(at 132.08 214.63 0)
			(effects
				(font
					(size 1.27 1.27)
					(thickness 0.15)
				)
				(justify left bottom)
				(hide yes)
			)
		)
		(property "Val" "0R"
			(at 110.49 193.04 0)
			(effects
				(font
					(size 1.27 1.27)
					(thickness 0.15)
				)
			)
		)
		(property "License" "Apache-2.0"
			(at 132.08 219.71 0)
			(effects
				(font
					(size 1.27 1.27)
					(thickness 0.15)
				)
				(justify left bottom)
				(hide yes)
			)
		)
		(property "Author" "Antmicro"
			(at 132.08 222.25 0)
			(effects
				(font
					(size 1.27 1.27)
					(thickness 0.15)
				)
				(justify left bottom)
				(hide yes)
			)
		)
		(property "Tolerance" "~"
			(at 132.08 204.47 0)
			(effects
				(font
					(size 1.27 1.27)
				)
				(justify left bottom)
				(hide yes)
			)
		)
		(property "Current" "1A"
			(at 132.08 224.79 0)
			(effects
				(font
					(size 1.27 1.27)
					(thickness 0.15)
				)
				(justify left bottom)
				(hide yes)
			)
		)
		(pin "1"
		)
		(pin "2"
		)
		(instances
			(project "k410t-devboard"
				(path ""
					(reference "R83")
					(unit 1)
				)
			)
		)
	)
	(symbol
		(lib_id "antmicroResistors0402:R_10k_0402")
		(at 238.76 81.28 180)
		(unit 1)
		(exclude_from_sim no)
		(in_bom yes)
		(on_board yes)
		(dnp no)
		(property "Reference" "R90"
			(at 240.665 80.01 0)
			(effects
				(font
					(size 1.27 1.27)
				)
			)
		)
		(property "Value" "R_10k_0402"
			(at 218.44 68.58 0)
			(effects
				(font
					(size 1.27 1.27)
					(thickness 0.15)
				)
				(justify left bottom)
				(hide yes)
			)
		)
		(property "Footprint" "antmicro-footprints:R_0402_1005Metric"
			(at 218.44 66.04 0)
			(effects
				(font
					(size 1.27 1.27)
					(thickness 0.15)
				)
				(justify left bottom)
				(hide yes)
			)
		)
		(property "Datasheet" "https://www.bourns.com/docs/product-datasheets/cr.pdf"
			(at 218.44 63.5 0)
			(effects
				(font
					(size 1.27 1.27)
					(thickness 0.15)
				)
				(justify left bottom)
				(hide yes)
			)
		)
		(property "Description" ""
			(at 238.76 81.28 0)
			(effects
				(font
					(size 1.27 1.27)
				)
			)
		)
		(property "Manufacturer" "Bourns"
			(at 218.44 58.42 0)
			(effects
				(font
					(size 1.27 1.27)
					(thickness 0.15)
				)
				(justify left bottom)
				(hide yes)
			)
		)
		(property "MPN" "CR0402-FX-1002GLF"
			(at 218.44 60.96 0)
			(effects
				(font
					(size 1.27 1.27)
					(thickness 0.15)
				)
				(justify left bottom)
				(hide yes)
			)
		)
		(property "Val" "10k"
			(at 231.775 80.01 0)
			(effects
				(font
					(size 1.27 1.27)
					(thickness 0.15)
				)
			)
		)
		(property "License" "Apache-2.0"
			(at 218.44 55.88 0)
			(effects
				(font
					(size 1.27 1.27)
					(thickness 0.15)
				)
				(justify left bottom)
				(hide yes)
			)
		)
		(property "Author" "Antmicro"
			(at 218.44 53.34 0)
			(effects
				(font
					(size 1.27 1.27)
					(thickness 0.15)
				)
				(justify left bottom)
				(hide yes)
			)
		)
		(property "Tolerance" "1%"
			(at 218.44 71.12 0)
			(effects
				(font
					(size 1.27 1.27)
				)
				(justify left bottom)
				(hide yes)
			)
		)
		(pin "1"
		)
		(pin "2"
		)
		(instances
			(project "k410t-devboard"
				(path ""
					(reference "R90")
					(unit 1)
				)
			)
		)
	)
	(symbol
		(lib_id "antmicroMemoryConnectorsPCCardSockets:DM3AT-SF-PEJM5")
		(at 344.17 66.04 0)
		(unit 1)
		(exclude_from_sim no)
		(in_bom yes)
		(on_board yes)
		(dnp no)
		(fields_autoplaced yes)
		(property "Reference" "J23"
			(at 366.395 54.61 0)
			(effects
				(font
					(size 1.27 1.27)
				)
			)
		)
		(property "Value" "DM3AT-SF-PEJM5"
			(at 366.395 57.15 0)
			(effects
				(font
					(size 1.27 1.27)
					(thickness 0.15)
				)
				(hide yes)
			)
		)
		(property "Footprint" "antmicro-footprints:MicroSD_DM3AT-SF-PEJM5"
			(at 401.32 71.12 0)
			(effects
				(font
					(size 1.27 1.27)
					(thickness 0.15)
				)
				(justify left bottom)
				(hide yes)
			)
		)
		(property "Datasheet" "https://www.hirose.com/en/product/document?clcode=CL0609-0031-0-00&productname=DM3AT-SF-PEJM5&series=DM3&documenttype=2DDrawing&lang=en&documentid=0000947170"
			(at 401.32 73.66 0)
			(effects
				(font
					(size 1.27 1.27)
					(thickness 0.15)
				)
				(justify left bottom)
				(hide yes)
			)
		)
		(property "Description" ""
			(at 344.17 66.04 0)
			(effects
				(font
					(size 1.27 1.27)
				)
			)
		)
		(property "Manufacturer" "Hirose Electric"
			(at 401.32 76.2 0)
			(effects
				(font
					(size 1.27 1.27)
					(thickness 0.15)
				)
				(justify left bottom)
				(hide yes)
			)
		)
		(property "MPN" "DM3AT-SF-PEJM5"
			(at 366.395 57.15 0)
			(effects
				(font
					(size 1.27 1.27)
					(thickness 0.15)
				)
			)
		)
		(property "Author" "Antmicro"
			(at 401.32 81.28 0)
			(effects
				(font
					(size 1.27 1.27)
					(thickness 0.15)
				)
				(justify left bottom)
				(hide yes)
			)
		)
		(property "License" "Apache-2.0"
			(at 401.32 83.82 0)
			(effects
				(font
					(size 1.27 1.27)
					(thickness 0.15)
				)
				(justify left bottom)
				(hide yes)
			)
		)
		(pin "1"
		)
		(pin "10"
		)
		(pin "11"
		)
		(pin "2"
		)
		(pin "3"
		)
		(pin "4"
		)
		(pin "5"
		)
		(pin "6"
		)
		(pin "7"
		)
		(pin "8"
		)
		(pin "9"
		)
		(instances
			(project "k410t-devboard"
				(path ""
					(reference "J23")
					(unit 1)
				)
			)
		)
	)
	(symbol
		(lib_id "antmicroResistors0402:R_10k_0402")
		(at 92.71 60.96 90)
		(unit 1)
		(exclude_from_sim no)
		(in_bom yes)
		(on_board yes)
		(dnp no)
		(property "Reference" "R68"
			(at 93.98 57.15 90)
			(effects
				(font
					(size 1.27 1.27)
				)
				(justify right)
			)
		)
		(property "Value" "R_10k_0402"
			(at 105.41 40.64 0)
			(effects
				(font
					(size 1.27 1.27)
					(thickness 0.15)
				)
				(justify left bottom)
				(hide yes)
			)
		)
		(property "Footprint" "antmicro-footprints:R_0402_1005Metric"
			(at 107.95 40.64 0)
			(effects
				(font
					(size 1.27 1.27)
					(thickness 0.15)
				)
				(justify left bottom)
				(hide yes)
			)
		)
		(property "Datasheet" "https://www.bourns.com/docs/product-datasheets/cr.pdf"
			(at 110.49 40.64 0)
			(effects
				(font
					(size 1.27 1.27)
					(thickness 0.15)
				)
				(justify left bottom)
				(hide yes)
			)
		)
		(property "Description" ""
			(at 92.71 60.96 0)
			(effects
				(font
					(size 1.27 1.27)
				)
			)
		)
		(property "Manufacturer" "Bourns"
			(at 115.57 40.64 0)
			(effects
				(font
					(size 1.27 1.27)
					(thickness 0.15)
				)
				(justify left bottom)
				(hide yes)
			)
		)
		(property "MPN" "CR0402-FX-1002GLF"
			(at 113.03 40.64 0)
			(effects
				(font
					(size 1.27 1.27)
					(thickness 0.15)
				)
				(justify left bottom)
				(hide yes)
			)
		)
		(property "Val" "10k"
			(at 93.98 59.69 90)
			(effects
				(font
					(size 1.27 1.27)
					(thickness 0.15)
				)
				(justify right)
			)
		)
		(property "License" "Apache-2.0"
			(at 118.11 40.64 0)
			(effects
				(font
					(size 1.27 1.27)
					(thickness 0.15)
				)
				(justify left bottom)
				(hide yes)
			)
		)
		(property "Author" "Antmicro"
			(at 120.65 40.64 0)
			(effects
				(font
					(size 1.27 1.27)
					(thickness 0.15)
				)
				(justify left bottom)
				(hide yes)
			)
		)
		(property "Tolerance" "1%"
			(at 102.87 40.64 0)
			(effects
				(font
					(size 1.27 1.27)
				)
				(justify left bottom)
				(hide yes)
			)
		)
		(pin "1"
		)
		(pin "2"
		)
		(instances
			(project "k410t-devboard"
				(path ""
					(reference "R68")
					(unit 1)
				)
			)
		)
	)
	(symbol
		(lib_id "antmicroResistors0402:R_100R_0402")
		(at 396.24 96.52 90)
		(unit 1)
		(exclude_from_sim no)
		(in_bom yes)
		(on_board yes)
		(dnp no)
		(property "Reference" "R253"
			(at 397.51 92.71 90)
			(effects
				(font
					(size 1.27 1.27)
				)
				(justify right)
			)
		)
		(property "Value" "R_100R_0402"
			(at 408.94 76.2 0)
			(effects
				(font
					(size 1.27 1.27)
					(thickness 0.15)
				)
				(justify left bottom)
				(hide yes)
			)
		)
		(property "Footprint" "antmicro-footprints:R_0402_1005Metric"
			(at 411.48 76.2 0)
			(effects
				(font
					(size 1.27 1.27)
					(thickness 0.15)
				)
				(justify left bottom)
				(hide yes)
			)
		)
		(property "Datasheet" "https://www.bourns.com/docs/product-datasheets/cr.pdf"
			(at 414.02 76.2 0)
			(effects
				(font
					(size 1.27 1.27)
					(thickness 0.15)
				)
				(justify left bottom)
				(hide yes)
			)
		)
		(property "Description" ""
			(at 396.24 96.52 0)
			(effects
				(font
					(size 1.27 1.27)
				)
			)
		)
		(property "Manufacturer" "Bourns"
			(at 419.1 76.2 0)
			(effects
				(font
					(size 1.27 1.27)
					(thickness 0.15)
				)
				(justify left bottom)
				(hide yes)
			)
		)
		(property "MPN" "CR0402-FX-1000GLF"
			(at 416.56 76.2 0)
			(effects
				(font
					(size 1.27 1.27)
					(thickness 0.15)
				)
				(justify left bottom)
				(hide yes)
			)
		)
		(property "Val" "100R"
			(at 397.51 95.25 90)
			(effects
				(font
					(size 1.27 1.27)
					(thickness 0.15)
				)
				(justify right)
			)
		)
		(property "License" "Apache-2.0"
			(at 421.64 76.2 0)
			(effects
				(font
					(size 1.27 1.27)
					(thickness 0.15)
				)
				(justify left bottom)
				(hide yes)
			)
		)
		(property "Author" "Antmicro"
			(at 424.18 76.2 0)
			(effects
				(font
					(size 1.27 1.27)
					(thickness 0.15)
				)
				(justify left bottom)
				(hide yes)
			)
		)
		(property "Tolerance" "1%"
			(at 406.4 76.2 0)
			(effects
				(font
					(size 1.27 1.27)
				)
				(justify left bottom)
				(hide yes)
			)
		)
		(pin "1"
		)
		(pin "2"
		)
		(instances
			(project "k410t-devboard"
				(path ""
					(reference "R253")
					(unit 1)
				)
			)
		)
	)
	(symbol
		(lib_id "antmicroResistors0402:R_100R_0402")
		(at 101.6 208.28 90)
		(unit 1)
		(exclude_from_sim no)
		(in_bom no)
		(on_board yes)
		(dnp yes)
		(property "Reference" "R73"
			(at 102.87 204.47 90)
			(effects
				(font
					(size 1.27 1.27)
				)
				(justify right)
			)
		)
		(property "Value" "R_100R_0402"
			(at 114.3 187.96 0)
			(effects
				(font
					(size 1.27 1.27)
					(thickness 0.15)
				)
				(justify left bottom)
				(hide yes)
			)
		)
		(property "Footprint" "antmicro-footprints:R_0402_1005Metric"
			(at 116.84 187.96 0)
			(effects
				(font
					(size 1.27 1.27)
					(thickness 0.15)
				)
				(justify left bottom)
				(hide yes)
			)
		)
		(property "Datasheet" "https://www.bourns.com/docs/product-datasheets/cr.pdf"
			(at 119.38 187.96 0)
			(effects
				(font
					(size 1.27 1.27)
					(thickness 0.15)
				)
				(justify left bottom)
				(hide yes)
			)
		)
		(property "Description" ""
			(at 101.6 208.28 0)
			(effects
				(font
					(size 1.27 1.27)
				)
			)
		)
		(property "Manufacturer" "Bourns"
			(at 124.46 187.96 0)
			(effects
				(font
					(size 1.27 1.27)
					(thickness 0.15)
				)
				(justify left bottom)
				(hide yes)
			)
		)
		(property "MPN" "CR0402-FX-1000GLF"
			(at 121.92 187.96 0)
			(effects
				(font
					(size 1.27 1.27)
					(thickness 0.15)
				)
				(justify left bottom)
				(hide yes)
			)
		)
		(property "Val" "100R"
			(at 102.87 207.01 90)
			(effects
				(font
					(size 1.27 1.27)
					(thickness 0.15)
				)
				(justify right)
			)
		)
		(property "License" "Apache-2.0"
			(at 127 187.96 0)
			(effects
				(font
					(size 1.27 1.27)
					(thickness 0.15)
				)
				(justify left bottom)
				(hide yes)
			)
		)
		(property "Author" "Antmicro"
			(at 129.54 187.96 0)
			(effects
				(font
					(size 1.27 1.27)
					(thickness 0.15)
				)
				(justify left bottom)
				(hide yes)
			)
		)
		(property "Tolerance" "1%"
			(at 111.76 187.96 0)
			(effects
				(font
					(size 1.27 1.27)
				)
				(justify left bottom)
				(hide yes)
			)
		)
		(property "DNP" "DNP"
			(at 101.6 205.74 0)
			(effects
				(font
					(size 1.27 1.27)
				)
			)
		)
		(pin "1"
		)
		(pin "2"
		)
		(instances
			(project "k410t-devboard"
				(path ""
					(reference "R73")
					(unit 1)
				)
			)
		)
	)
	(symbol
		(lib_id "antmicroResistors0402:R_10k_0402")
		(at 238.76 76.2 180)
		(unit 1)
		(exclude_from_sim no)
		(in_bom yes)
		(on_board yes)
		(dnp no)
		(property "Reference" "R89"
			(at 240.665 74.93 0)
			(effects
				(font
					(size 1.27 1.27)
				)
			)
		)
		(property "Value" "R_10k_0402"
			(at 218.44 63.5 0)
			(effects
				(font
					(size 1.27 1.27)
					(thickness 0.15)
				)
				(justify left bottom)
				(hide yes)
			)
		)
		(property "Footprint" "antmicro-footprints:R_0402_1005Metric"
			(at 218.44 60.96 0)
			(effects
				(font
					(size 1.27 1.27)
					(thickness 0.15)
				)
				(justify left bottom)
				(hide yes)
			)
		)
		(property "Datasheet" "https://www.bourns.com/docs/product-datasheets/cr.pdf"
			(at 218.44 58.42 0)
			(effects
				(font
					(size 1.27 1.27)
					(thickness 0.15)
				)
				(justify left bottom)
				(hide yes)
			)
		)
		(property "Description" ""
			(at 238.76 76.2 0)
			(effects
				(font
					(size 1.27 1.27)
				)
			)
		)
		(property "Manufacturer" "Bourns"
			(at 218.44 53.34 0)
			(effects
				(font
					(size 1.27 1.27)
					(thickness 0.15)
				)
				(justify left bottom)
				(hide yes)
			)
		)
		(property "MPN" "CR0402-FX-1002GLF"
			(at 218.44 55.88 0)
			(effects
				(font
					(size 1.27 1.27)
					(thickness 0.15)
				)
				(justify left bottom)
				(hide yes)
			)
		)
		(property "Val" "10k"
			(at 231.775 74.93 0)
			(effects
				(font
					(size 1.27 1.27)
					(thickness 0.15)
				)
			)
		)
		(property "License" "Apache-2.0"
			(at 218.44 50.8 0)
			(effects
				(font
					(size 1.27 1.27)
					(thickness 0.15)
				)
				(justify left bottom)
				(hide yes)
			)
		)
		(property "Author" "Antmicro"
			(at 218.44 48.26 0)
			(effects
				(font
					(size 1.27 1.27)
					(thickness 0.15)
				)
				(justify left bottom)
				(hide yes)
			)
		)
		(property "Tolerance" "1%"
			(at 218.44 66.04 0)
			(effects
				(font
					(size 1.27 1.27)
				)
				(justify left bottom)
				(hide yes)
			)
		)
		(pin "1"
		)
		(pin "2"
		)
		(instances
			(project "k410t-devboard"
				(path ""
					(reference "R89")
					(unit 1)
				)
			)
		)
	)
	(symbol
		(lib_id "antmicroMemory:MT25QL256ABA1EW7-0SIT")
		(at 146.05 186.69 0)
		(unit 1)
		(exclude_from_sim no)
		(in_bom no)
		(on_board yes)
		(dnp yes)
		(fields_autoplaced yes)
		(property "Reference" "U13"
			(at 160.02 176.53 0)
			(effects
				(font
					(size 1.27 1.27)
				)
			)
		)
		(property "Value" "MT25QL256ABA1EW7-0SIT"
			(at 160.02 179.07 0)
			(effects
				(font
					(size 1.27 1.27)
					(thickness 0.15)
				)
			)
		)
		(property "Footprint" "antmicro-footprints:WDFN-8-1EP_6x5mm_P1.27mm_EP3.4x4mm"
			(at 187.96 194.31 0)
			(effects
				(font
					(size 1.27 1.27)
					(thickness 0.15)
				)
				(justify left bottom)
				(hide yes)
			)
		)
		(property "Datasheet" "https://www.micron.com/products/nor-flash/serial-nor-flash/part-catalog/mt25ql256aba1ew7-0sit"
			(at 187.96 196.85 0)
			(effects
				(font
					(size 1.27 1.27)
					(thickness 0.15)
				)
				(justify left bottom)
				(hide yes)
			)
		)
		(property "Description" ""
			(at 146.05 186.69 0)
			(effects
				(font
					(size 1.27 1.27)
				)
			)
		)
		(property "MPN" "MT25QL256ABA1EW7-0SIT"
			(at 187.96 199.39 0)
			(effects
				(font
					(size 1.27 1.27)
					(thickness 0.15)
				)
				(justify left bottom)
				(hide yes)
			)
		)
		(property "Manufacturer" "Micron Technology"
			(at 187.96 201.93 0)
			(effects
				(font
					(size 1.27 1.27)
					(thickness 0.15)
				)
				(justify left bottom)
				(hide yes)
			)
		)
		(property "Author" "Antmicro"
			(at 187.96 204.47 0)
			(effects
				(font
					(size 1.27 1.27)
					(thickness 0.15)
				)
				(justify left bottom)
				(hide yes)
			)
		)
		(property "License" "Apache-2.0"
			(at 187.96 207.01 0)
			(effects
				(font
					(size 1.27 1.27)
					(thickness 0.15)
				)
				(justify left bottom)
				(hide yes)
			)
		)
		(property "DNP" "DNP"
			(at 160.02 181.61 0)
			(effects
				(font
					(size 1.27 1.27)
				)
			)
		)
		(pin "1"
		)
		(pin "2"
		)
		(pin "3"
		)
		(pin "4"
		)
		(pin "5"
		)
		(pin "6"
		)
		(pin "7"
		)
		(pin "8"
		)
		(pin "9"
		)
		(instances
			(project "k410t-devboard"
				(path ""
					(reference "U13")
					(unit 1)
				)
			)
		)
	)
	(symbol
		(lib_id "antmicroResistorNetworksArrays:R_4x33R_0201_array")
		(at 293.37 76.2 0)
		(unit 1)
		(exclude_from_sim no)
		(in_bom yes)
		(on_board yes)
		(dnp no)
		(property "Reference" "R63"
			(at 298.45 59.69 0)
			(effects
				(font
					(size 1.27 1.27)
				)
			)
		)
		(property "Value" "R_4x33R_0201_array"
			(at 298.45 69.85 0)
			(effects
				(font
					(size 1.27 1.27)
					(thickness 0.15)
				)
				(hide yes)
			)
		)
		(property "Footprint" "antmicro-footprints:R_Array_4x0201_Panasonic_EXB18V"
			(at 320.04 86.995 0)
			(effects
				(font
					(size 1.27 1.27)
					(thickness 0.15)
				)
				(justify left bottom)
				(hide yes)
			)
		)
		(property "Datasheet" "http://industrial.panasonic.com/cdbs/www-data/pdf/AOC0000/AOC0000C14.pdf"
			(at 320.04 89.535 0)
			(effects
				(font
					(size 1.27 1.27)
					(thickness 0.15)
				)
				(justify left bottom)
				(hide yes)
			)
		)
		(property "Description" ""
			(at 293.37 76.2 0)
			(effects
				(font
					(size 1.27 1.27)
				)
			)
		)
		(property "MPN" "EXB-18V330JX"
			(at 320.04 92.075 0)
			(effects
				(font
					(size 1.27 1.27)
					(thickness 0.15)
				)
				(justify left bottom)
				(hide yes)
			)
		)
		(property "Manufacturer" "Panasonic"
			(at 320.04 94.615 0)
			(effects
				(font
					(size 1.27 1.27)
					(thickness 0.15)
				)
				(justify left bottom)
				(hide yes)
			)
		)
		(property "Author" "Antmicro"
			(at 320.04 97.155 0)
			(effects
				(font
					(size 1.27 1.27)
					(thickness 0.15)
				)
				(justify left bottom)
				(hide yes)
			)
		)
		(property "License" "Apache-2.0"
			(at 320.04 99.695 0)
			(effects
				(font
					(size 1.27 1.27)
					(thickness 0.15)
				)
				(justify left bottom)
				(hide yes)
			)
		)
		(property "Val" "R_4x33R_0201"
			(at 298.45 90.17 0)
			(effects
				(font
					(size 1.27 1.27)
				)
				(hide yes)
			)
		)
		(pin "1"
		)
		(pin "2"
		)
		(pin "3"
		)
		(pin "4"
		)
		(pin "5"
		)
		(pin "6"
		)
		(pin "7"
		)
		(pin "8"
		)
		(instances
			(project "k410t-devboard"
				(path ""
					(reference "R63")
					(unit 1)
				)
			)
		)
	)
	(symbol
		(lib_id "antmicroCapacitors0402:C_100n_0402")
		(at 382.27 195.58 90)
		(unit 1)
		(exclude_from_sim no)
		(in_bom yes)
		(on_board yes)
		(dnp no)
		(fields_autoplaced yes)
		(property "Reference" "C212"
			(at 384.81 191.7635 90)
			(effects
				(font
					(size 1.27 1.27)
				)
				(justify right)
			)
		)
		(property "Value" "C_100n_0402"
			(at 392.43 175.26 0)
			(effects
				(font
					(size 1.27 1.27)
					(thickness 0.15)
				)
				(justify left bottom)
				(hide yes)
			)
		)
		(property "Footprint" "antmicro-footprints:C_0402_1005Metric"
			(at 394.97 175.26 0)
			(effects
				(font
					(size 1.27 1.27)
					(thickness 0.15)
				)
				(justify left bottom)
				(hide yes)
			)
		)
		(property "Datasheet" "https://www.murata.com/products/productdetail?partno=GRM155R61H104KE14%23"
			(at 397.51 175.26 0)
			(effects
				(font
					(size 1.27 1.27)
					(thickness 0.15)
				)
				(justify left bottom)
				(hide yes)
			)
		)
		(property "Description" ""
			(at 382.27 195.58 0)
			(effects
				(font
					(size 1.27 1.27)
				)
			)
		)
		(property "Manufacturer" "Murata"
			(at 402.59 175.26 0)
			(effects
				(font
					(size 1.27 1.27)
					(thickness 0.15)
				)
				(justify left bottom)
				(hide yes)
			)
		)
		(property "MPN" "GRM155R61H104KE14D"
			(at 400.05 175.26 0)
			(effects
				(font
					(size 1.27 1.27)
					(thickness 0.15)
				)
				(justify left bottom)
				(hide yes)
			)
		)
		(property "Val" "100n"
			(at 384.81 194.3035 90)
			(effects
				(font
					(size 1.27 1.27)
					(thickness 0.15)
				)
				(justify right)
			)
		)
		(property "License" "Apache-2.0"
			(at 405.13 175.26 0)
			(effects
				(font
					(size 1.27 1.27)
					(thickness 0.15)
				)
				(justify left bottom)
				(hide yes)
			)
		)
		(property "Author" "Antmicro"
			(at 407.67 175.26 0)
			(effects
				(font
					(size 1.27 1.27)
					(thickness 0.15)
				)
				(justify left bottom)
				(hide yes)
			)
		)
		(property "Voltage" "50V"
			(at 410.21 175.26 0)
			(effects
				(font
					(size 1.27 1.27)
				)
				(justify left bottom)
				(hide yes)
			)
		)
		(property "Dielectric" "X5R"
			(at 412.75 175.26 0)
			(effects
				(font
					(size 1.27 1.27)
				)
				(justify left bottom)
				(hide yes)
			)
		)
		(pin "1"
		)
		(pin "2"
		)
		(instances
			(project "k410t-devboard"
				(path ""
					(reference "C212")
					(unit 1)
				)
			)
		)
	)
)
